FILE_TYPE = MACRO_DRAWING;
SET COLOR_WIRE YELLOW;
SET COLOR_PROP MONO;
SET COLOR_DOT WHITE;
SET COLOR_ARC YELLOW;
SET COLOR_BODY GREEN;
SET COLOR_NOTE MONO;
SET PROP_DISPLAY VALUE;
SET PAGE_NUMBER P107;
FORCEADD TAP..3
(-5525 2125);
FORCEPROP 3 LASTPIN (-5525 2075) SIG_NAME P3E_CPU0_PE1_SS_TXN<0>
J 0
(-5515 2085);
DISPLAY 0.659574 (-5515 2085);
PAINT MONO (-5515 2085);
DISPLAY INVISIBLE (-5515 2085);
FORCEPROP 1 LASTPIN (-5525 2075) BN 0
R 1
J 0
(-5532 2063);
DISPLAY 0.617021 (-5532 2063);
PAINT GREEN (-5532 2063);
FORCEPROP 1 LAST HDL_TAP TRUE
J 0
(-5205 1995);
DISPLAY 2.276596 (-5205 1995);
PAINT GREEN (-5205 1995);
DISPLAY INVISIBLE (-5205 1995);
FORCEPROP 2 LAST CDS_LIB mstr_standard
J 0
(-5525 2125);
PAINT ORANGE (-5525 2125);
DISPLAY INVISIBLE (-5525 2125);
FORCEPROP 1 LAST BODY_TYPE PLUMBING
J 0
(-5475 2075);
DISPLAY 2.276596 (-5475 2075);
PAINT GREEN (-5475 2075);
DISPLAY INVISIBLE (-5475 2075);
FORCEPROP 1 LAST PATH I198
J 0
(-5527 2125);
DISPLAY 0.872340 (-5527 2125);
PAINT GREEN (-5527 2125);
DISPLAY INVISIBLE (-5527 2125);
FORCEADD TAP..3
(-5725 2125);
FORCEPROP 3 LASTPIN (-5725 2075) SIG_NAME P3E_CPU0_PE1_SS_TXN<1>
J 0
(-5715 2085);
DISPLAY 0.659574 (-5715 2085);
PAINT MONO (-5715 2085);
DISPLAY INVISIBLE (-5715 2085);
FORCEPROP 1 LASTPIN (-5725 2075) BN 1
R 1
J 0
(-5732 2063);
DISPLAY 0.617021 (-5732 2063);
PAINT GREEN (-5732 2063);
FORCEPROP 1 LAST HDL_TAP TRUE
J 0
(-5405 1995);
DISPLAY 2.276596 (-5405 1995);
PAINT GREEN (-5405 1995);
DISPLAY INVISIBLE (-5405 1995);
FORCEPROP 1 LAST BODY_TYPE PLUMBING
J 0
(-5675 2075);
DISPLAY 2.276596 (-5675 2075);
PAINT GREEN (-5675 2075);
DISPLAY INVISIBLE (-5675 2075);
FORCEPROP 2 LAST CDS_LIB mstr_standard
J 0
(-5725 2125);
PAINT ORANGE (-5725 2125);
DISPLAY INVISIBLE (-5725 2125);
FORCEPROP 1 LAST PATH I199
J 0
(-5727 2125);
DISPLAY 0.872340 (-5727 2125);
PAINT GREEN (-5727 2125);
DISPLAY INVISIBLE (-5727 2125);
FORCEADD TAP..3
(-5925 2125);
FORCEPROP 3 LASTPIN (-5925 2075) SIG_NAME P3E_CPU0_PE1_SS_TXN<2>
J 0
(-5915 2085);
DISPLAY 0.659574 (-5915 2085);
PAINT MONO (-5915 2085);
DISPLAY INVISIBLE (-5915 2085);
FORCEPROP 1 LASTPIN (-5925 2075) BN 2
R 1
J 0
(-5932 2063);
DISPLAY 0.617021 (-5932 2063);
PAINT GREEN (-5932 2063);
FORCEPROP 1 LAST HDL_TAP TRUE
J 0
(-5605 1995);
DISPLAY 2.276596 (-5605 1995);
PAINT GREEN (-5605 1995);
DISPLAY INVISIBLE (-5605 1995);
FORCEPROP 2 LAST CDS_LIB mstr_standard
J 0
(-5925 2125);
PAINT ORANGE (-5925 2125);
DISPLAY INVISIBLE (-5925 2125);
FORCEPROP 1 LAST PATH I200
J 0
(-5927 2125);
DISPLAY 0.872340 (-5927 2125);
PAINT GREEN (-5927 2125);
DISPLAY INVISIBLE (-5927 2125);
FORCEPROP 1 LAST BODY_TYPE PLUMBING
J 0
(-5875 2075);
DISPLAY 2.276596 (-5875 2075);
PAINT GREEN (-5875 2075);
DISPLAY INVISIBLE (-5875 2075);
FORCEADD TAP..3
(-6125 2125);
FORCEPROP 3 LASTPIN (-6125 2075) SIG_NAME P3E_CPU0_PE1_SS_TXN<3>
J 0
(-6115 2085);
DISPLAY 0.659574 (-6115 2085);
PAINT MONO (-6115 2085);
DISPLAY INVISIBLE (-6115 2085);
FORCEPROP 1 LASTPIN (-6125 2075) BN 3
R 1
J 0
(-6132 2063);
DISPLAY 0.617021 (-6132 2063);
PAINT GREEN (-6132 2063);
FORCEPROP 1 LAST HDL_TAP TRUE
J 0
(-5805 1995);
DISPLAY 2.276596 (-5805 1995);
PAINT GREEN (-5805 1995);
DISPLAY INVISIBLE (-5805 1995);
FORCEPROP 2 LAST CDS_LIB mstr_standard
J 0
(-6125 2125);
PAINT ORANGE (-6125 2125);
DISPLAY INVISIBLE (-6125 2125);
FORCEPROP 1 LAST BODY_TYPE PLUMBING
J 0
(-6075 2075);
DISPLAY 2.276596 (-6075 2075);
PAINT GREEN (-6075 2075);
DISPLAY INVISIBLE (-6075 2075);
FORCEPROP 1 LAST PATH I201
J 0
(-6127 2125);
DISPLAY 0.872340 (-6127 2125);
PAINT GREEN (-6127 2125);
DISPLAY INVISIBLE (-6127 2125);
FORCEADD TAP..3
(-6325 2125);
FORCEPROP 3 LASTPIN (-6325 2075) SIG_NAME P3E_CPU0_PE1_SS_TXN<4>
J 0
(-6315 2085);
DISPLAY 0.659574 (-6315 2085);
PAINT MONO (-6315 2085);
DISPLAY INVISIBLE (-6315 2085);
FORCEPROP 1 LASTPIN (-6325 2075) BN 4
R 1
J 0
(-6332 2063);
DISPLAY 0.617021 (-6332 2063);
PAINT GREEN (-6332 2063);
FORCEPROP 2 LAST CDS_LIB mstr_standard
J 0
(-6325 2125);
PAINT ORANGE (-6325 2125);
DISPLAY INVISIBLE (-6325 2125);
FORCEPROP 1 LAST BODY_TYPE PLUMBING
J 0
(-6275 2075);
DISPLAY 2.276596 (-6275 2075);
PAINT GREEN (-6275 2075);
DISPLAY INVISIBLE (-6275 2075);
FORCEPROP 1 LAST PATH I202
J 0
(-6327 2125);
DISPLAY 0.872340 (-6327 2125);
PAINT GREEN (-6327 2125);
DISPLAY INVISIBLE (-6327 2125);
FORCEPROP 1 LAST HDL_TAP TRUE
J 0
(-6005 1995);
DISPLAY 2.276596 (-6005 1995);
PAINT GREEN (-6005 1995);
DISPLAY INVISIBLE (-6005 1995);
FORCEADD TAP..3
(-6525 2125);
FORCEPROP 3 LASTPIN (-6525 2075) SIG_NAME P3E_CPU0_PE1_SS_TXN<5>
J 0
(-6515 2085);
DISPLAY 0.659574 (-6515 2085);
PAINT MONO (-6515 2085);
DISPLAY INVISIBLE (-6515 2085);
FORCEPROP 1 LASTPIN (-6525 2075) BN 5
R 1
J 0
(-6532 2063);
DISPLAY 0.617021 (-6532 2063);
PAINT GREEN (-6532 2063);
FORCEPROP 1 LAST HDL_TAP TRUE
J 0
(-6205 1995);
DISPLAY 2.276596 (-6205 1995);
PAINT GREEN (-6205 1995);
DISPLAY INVISIBLE (-6205 1995);
FORCEPROP 2 LAST CDS_LIB mstr_standard
J 0
(-6525 2125);
PAINT ORANGE (-6525 2125);
DISPLAY INVISIBLE (-6525 2125);
FORCEPROP 1 LAST BODY_TYPE PLUMBING
J 0
(-6475 2075);
DISPLAY 2.276596 (-6475 2075);
PAINT GREEN (-6475 2075);
DISPLAY INVISIBLE (-6475 2075);
FORCEPROP 1 LAST PATH I203
J 0
(-6527 2125);
DISPLAY 0.872340 (-6527 2125);
PAINT GREEN (-6527 2125);
DISPLAY INVISIBLE (-6527 2125);
FORCEADD TAP..3
(-6725 2125);
FORCEPROP 3 LASTPIN (-6725 2075) SIG_NAME P3E_CPU0_PE1_SS_TXN<6>
J 0
(-6715 2085);
DISPLAY 0.659574 (-6715 2085);
PAINT MONO (-6715 2085);
DISPLAY INVISIBLE (-6715 2085);
FORCEPROP 1 LASTPIN (-6725 2075) BN 6
R 1
J 0
(-6732 2063);
DISPLAY 0.617021 (-6732 2063);
PAINT GREEN (-6732 2063);
FORCEPROP 1 LAST HDL_TAP TRUE
J 0
(-6405 1995);
DISPLAY 2.276596 (-6405 1995);
PAINT GREEN (-6405 1995);
DISPLAY INVISIBLE (-6405 1995);
FORCEPROP 2 LAST CDS_LIB mstr_standard
J 0
(-6725 2125);
PAINT ORANGE (-6725 2125);
DISPLAY INVISIBLE (-6725 2125);
FORCEPROP 1 LAST BODY_TYPE PLUMBING
J 0
(-6675 2075);
DISPLAY 2.276596 (-6675 2075);
PAINT GREEN (-6675 2075);
DISPLAY INVISIBLE (-6675 2075);
FORCEPROP 1 LAST PATH I204
J 0
(-6727 2125);
DISPLAY 0.872340 (-6727 2125);
PAINT GREEN (-6727 2125);
DISPLAY INVISIBLE (-6727 2125);
FORCEADD TAP..3
(-6925 2125);
FORCEPROP 3 LASTPIN (-6925 2075) SIG_NAME P3E_CPU0_PE1_SS_TXN<7>
J 0
(-6915 2085);
DISPLAY 0.659574 (-6915 2085);
PAINT MONO (-6915 2085);
DISPLAY INVISIBLE (-6915 2085);
FORCEPROP 1 LASTPIN (-6925 2075) BN 7
R 1
J 0
(-6932 2063);
DISPLAY 0.617021 (-6932 2063);
PAINT GREEN (-6932 2063);
FORCEPROP 1 LAST HDL_TAP TRUE
J 0
(-6605 1995);
DISPLAY 2.276596 (-6605 1995);
PAINT GREEN (-6605 1995);
DISPLAY INVISIBLE (-6605 1995);
FORCEPROP 2 LAST CDS_LIB mstr_standard
J 0
(-6925 2125);
PAINT ORANGE (-6925 2125);
DISPLAY INVISIBLE (-6925 2125);
FORCEPROP 1 LAST PATH I205
J 0
(-6927 2125);
DISPLAY 0.872340 (-6927 2125);
PAINT GREEN (-6927 2125);
DISPLAY INVISIBLE (-6927 2125);
FORCEPROP 1 LAST BODY_TYPE PLUMBING
J 0
(-6875 2075);
DISPLAY 2.276596 (-6875 2075);
PAINT GREEN (-6875 2075);
DISPLAY INVISIBLE (-6875 2075);
FORCEADD OFFPAGE..1
(-7100 2175);
FORCEPROP 2 LAST $XR0 30 
J 0
(-7321 2175);
DISPLAY 0.638298 (-7321 2175);
PAINT MONO (-7321 2175);
FORCEPROP 2 LAST $XR1 107 
J 0
(-7441 2175);
DISPLAY 0.638298 (-7441 2175);
PAINT MONO (-7441 2175);
FORCEPROP 1 LAST OFFPAGE TRUE
J 0
(-6780 2045);
PAINT GREEN (-6780 2045);
DISPLAY INVISIBLE (-6780 2045);
FORCEPROP 2 LAST PATH I206
J 0
(-7050 2250);
DISPLAY 1.021277 (-7050 2250);
PAINT ORANGE (-7050 2250);
DISPLAY INVISIBLE (-7050 2250);
FORCEPROP 2 LAST CDS_LIB mstr_standard
J 0
(-7100 2175);
PAINT ORANGE (-7100 2175);
DISPLAY INVISIBLE (-7100 2175);
FORCEPROP 1 LAST COMMENT_BODY TRUE
J 0
(-6980 2075);
DISPLAY 2.276596 (-6980 2075);
PAINT GREEN (-6980 2075);
DISPLAY INVISIBLE (-6980 2075);
FORCEADD CAP..1
R 2
(-5525 1875);
FORCEPROP 1 LAST LOCATION C3P13
J 2
(-5575 1975);
DISPLAY 0.617021 (-5575 1975);
PAINT AQUA (-5575 1975);
FORCEPROP 1 LAST PART_NUMBER A36096-155
J 2
(-5575 1725);
DISPLAY 0.617021 (-5575 1725);
PAINT BLUE (-5575 1725);
FORCEPROP 1 LAST VALUE 0.22UF
J 2
(-5575 1925);
DISPLAY 0.617021 (-5575 1925);
PAINT SKYBLUE (-5575 1925);
FORCEPROP 1 LAST TOLERANCE 10%
J 2
(-5575 1825);
DISPLAY 0.617021 (-5575 1825);
PAINT SKYBLUE (-5575 1825);
FORCEPROP 1 LAST PACK_TYPE 0402
J 2
(-5575 1675);
DISPLAY 0.617021 (-5575 1675);
PAINT SKYBLUE (-5575 1675);
FORCEPROP 1 LAST VOLTAGE 16V
J 2
(-5575 1875);
DISPLAY 0.617021 (-5575 1875);
PAINT SKYBLUE (-5575 1875);
FORCEPROP 1 LAST MATERIAL X7R
J 2
(-5575 1775);
DISPLAY 0.617021 (-5575 1775);
PAINT SKYBLUE (-5575 1775);
FORCEPROP 1 LASTPIN (-5525 1775) $PN 2
J 2
(-5535 1755);
DISPLAY 0.787234 (-5535 1755);
PAINT ORANGE (-5535 1755);
DISPLAY INVISIBLE (-5535 1755);
FORCEPROP 1 LASTPIN (-5525 1975) $PN 1
J 2
(-5535 1955);
DISPLAY 0.787234 (-5535 1955);
PAINT ORANGE (-5535 1955);
DISPLAY INVISIBLE (-5535 1955);
FORCEPROP 2 LAST CDS_LIB mstr_discrete
J 0
(-5525 1875);
PAINT ORANGE (-5525 1875);
DISPLAY INVISIBLE (-5525 1875);
FORCEPROP 2 LAST CDS_LOCATION C3P13
J 2
(-5575 1975);
DISPLAY 0.617021 (-5575 1975);
PAINT AQUA (-5575 1975);
DISPLAY INVISIBLE (-5575 1975);
FORCEPROP 1 LAST PATH I207
J 2
(-5575 2025);
DISPLAY 0.978723 (-5575 2025);
PAINT WHITE (-5575 2025);
DISPLAY INVISIBLE (-5575 2025);
FORCEPROP 2 LAST CDS_SEC 1
J 0
(-5575 2075);
DISPLAY 1.021277 (-5575 2075);
PAINT ORANGE (-5575 2075);
DISPLAY INVISIBLE (-5575 2075);
FORCEPROP 2 LAST $SEC 1
J 0
(-5575 2075);
DISPLAY 0.680851 (-5575 2075);
PAINT MONO (-5575 2075);
DISPLAY INVISIBLE (-5575 2075);
FORCEADD CAP..1
R 2
(-5725 1575);
FORCEPROP 1 LAST PART_NUMBER A36096-155
J 2
(-5775 1425);
DISPLAY 0.617021 (-5775 1425);
PAINT BLUE (-5775 1425);
FORCEPROP 1 LAST PACK_TYPE 0402
J 2
(-5775 1375);
DISPLAY 0.617021 (-5775 1375);
PAINT SKYBLUE (-5775 1375);
FORCEPROP 1 LAST MATERIAL X7R
J 2
(-5775 1475);
DISPLAY 0.617021 (-5775 1475);
PAINT SKYBLUE (-5775 1475);
FORCEPROP 1 LAST TOLERANCE 10%
J 2
(-5775 1525);
DISPLAY 0.617021 (-5775 1525);
PAINT SKYBLUE (-5775 1525);
FORCEPROP 1 LAST LOCATION C3P17
J 2
(-5775 1675);
DISPLAY 0.617021 (-5775 1675);
PAINT AQUA (-5775 1675);
FORCEPROP 1 LAST VALUE 0.22UF
J 2
(-5775 1625);
DISPLAY 0.617021 (-5775 1625);
PAINT SKYBLUE (-5775 1625);
FORCEPROP 1 LAST VOLTAGE 16V
J 2
(-5775 1575);
DISPLAY 0.617021 (-5775 1575);
PAINT SKYBLUE (-5775 1575);
FORCEPROP 1 LASTPIN (-5725 1475) $PN 2
J 2
(-5735 1455);
DISPLAY 0.787234 (-5735 1455);
PAINT ORANGE (-5735 1455);
DISPLAY INVISIBLE (-5735 1455);
FORCEPROP 1 LASTPIN (-5725 1675) $PN 1
J 2
(-5735 1655);
DISPLAY 0.787234 (-5735 1655);
PAINT ORANGE (-5735 1655);
DISPLAY INVISIBLE (-5735 1655);
FORCEPROP 2 LAST CDS_LIB mstr_discrete
J 0
(-5725 1575);
PAINT ORANGE (-5725 1575);
DISPLAY INVISIBLE (-5725 1575);
FORCEPROP 2 LAST CDS_SEC 1
J 0
(-5775 1775);
DISPLAY 1.021277 (-5775 1775);
PAINT ORANGE (-5775 1775);
DISPLAY INVISIBLE (-5775 1775);
FORCEPROP 2 LAST $SEC 1
J 0
(-5775 1775);
DISPLAY 0.680851 (-5775 1775);
PAINT MONO (-5775 1775);
DISPLAY INVISIBLE (-5775 1775);
FORCEPROP 2 LAST CDS_LOCATION C3P17
J 2
(-5775 1675);
DISPLAY 0.617021 (-5775 1675);
PAINT AQUA (-5775 1675);
DISPLAY INVISIBLE (-5775 1675);
FORCEPROP 1 LAST PATH I208
J 2
(-5775 1725);
DISPLAY 0.978723 (-5775 1725);
PAINT WHITE (-5775 1725);
DISPLAY INVISIBLE (-5775 1725);
FORCEADD OFFPAGE..2
(-5275 1275);
FORCEPROP 2 LAST $XR0 117 
J 0
(-5086 1275);
DISPLAY 0.638298 (-5086 1275);
PAINT MONO (-5086 1275);
FORCEPROP 1 LAST COMMENT_BODY TRUE
J 0
(-5320 1180);
DISPLAY 0.872340 (-5320 1180);
PAINT GREEN (-5320 1180);
DISPLAY INVISIBLE (-5320 1180);
FORCEPROP 2 LAST CDS_LIB mstr_standard
J 0
(-5275 1275);
PAINT ORANGE (-5275 1275);
DISPLAY INVISIBLE (-5275 1275);
FORCEPROP 2 LAST PATH I209
J 0
(-5100 1350);
DISPLAY 1.021277 (-5100 1350);
PAINT ORANGE (-5100 1350);
DISPLAY INVISIBLE (-5100 1350);
FORCEPROP 1 LAST OFFPAGE TRUE
J 0
(-4950 1150);
DISPLAY 0.872340 (-4950 1150);
PAINT GREEN (-4950 1150);
DISPLAY INVISIBLE (-4950 1150);
FORCEADD TAP..7
(-5525 1325);
FORCEPROP 3 LASTPIN (-5525 1375) SIG_NAME P3E_CPU0_PE1_PCH_TXN<0>
J 0
(-5515 1385);
DISPLAY 0.659574 (-5515 1385);
PAINT MONO (-5515 1385);
DISPLAY INVISIBLE (-5515 1385);
FORCEPROP 1 LASTPIN (-5525 1375) BN 0
R 1
J 0
(-5532 1323);
DISPLAY 0.617021 (-5532 1323);
PAINT GREEN (-5532 1323);
FORCEPROP 2 LAST CDS_LIB mstr_standard
J 0
(-5525 1325);
PAINT ORANGE (-5525 1325);
DISPLAY INVISIBLE (-5525 1325);
FORCEPROP 1 LAST BODY_TYPE PLUMBING
J 0
(-5475 1325);
DISPLAY 2.276596 (-5475 1325);
PAINT GREEN (-5475 1325);
DISPLAY INVISIBLE (-5475 1325);
FORCEPROP 1 LAST PATH I210
J 0
(-5527 1325);
DISPLAY 0.872340 (-5527 1325);
PAINT GREEN (-5527 1325);
DISPLAY INVISIBLE (-5527 1325);
FORCEPROP 1 LAST HDL_TAP TRUE
J 0
(-5205 1195);
DISPLAY 2.276596 (-5205 1195);
PAINT GREEN (-5205 1195);
DISPLAY INVISIBLE (-5205 1195);
FORCEADD TAP..3
(-5475 1125);
FORCEPROP 3 LASTPIN (-5475 1075) SIG_NAME P3E_CPU0_PE1_SS_TXP<0>
J 0
(-5465 1085);
DISPLAY 0.659574 (-5465 1085);
PAINT MONO (-5465 1085);
DISPLAY INVISIBLE (-5465 1085);
FORCEPROP 1 LASTPIN (-5475 1075) BN 0
R 1
J 0
(-5482 1063);
DISPLAY 0.617021 (-5482 1063);
PAINT GREEN (-5482 1063);
FORCEPROP 1 LAST HDL_TAP TRUE
J 0
(-5155 995);
DISPLAY 2.276596 (-5155 995);
PAINT GREEN (-5155 995);
DISPLAY INVISIBLE (-5155 995);
FORCEPROP 1 LAST PATH I211
J 0
(-5477 1125);
DISPLAY 0.872340 (-5477 1125);
PAINT GREEN (-5477 1125);
DISPLAY INVISIBLE (-5477 1125);
FORCEPROP 1 LAST BODY_TYPE PLUMBING
J 0
(-5425 1075);
DISPLAY 2.276596 (-5425 1075);
PAINT GREEN (-5425 1075);
DISPLAY INVISIBLE (-5425 1075);
FORCEPROP 2 LAST CDS_LIB mstr_standard
J 0
(-5475 1125);
PAINT ORANGE (-5475 1125);
DISPLAY INVISIBLE (-5475 1125);
FORCEADD CAP..1
R 2
(-5475 875);
FORCEPROP 1 LAST LOCATION C3P11
J 2
(-5525 975);
DISPLAY 0.617021 (-5525 975);
PAINT AQUA (-5525 975);
FORCEPROP 1 LAST PART_NUMBER A36096-155
J 2
(-5525 725);
DISPLAY 0.617021 (-5525 725);
PAINT BLUE (-5525 725);
FORCEPROP 1 LAST VALUE 0.22UF
J 2
(-5525 925);
DISPLAY 0.617021 (-5525 925);
PAINT SKYBLUE (-5525 925);
FORCEPROP 1 LAST PACK_TYPE 0402
J 2
(-5525 675);
DISPLAY 0.617021 (-5525 675);
PAINT SKYBLUE (-5525 675);
FORCEPROP 1 LAST TOLERANCE 10%
J 2
(-5525 825);
DISPLAY 0.617021 (-5525 825);
PAINT SKYBLUE (-5525 825);
FORCEPROP 1 LAST VOLTAGE 16V
J 2
(-5525 875);
DISPLAY 0.617021 (-5525 875);
PAINT SKYBLUE (-5525 875);
FORCEPROP 1 LAST MATERIAL X7R
J 2
(-5525 775);
DISPLAY 0.617021 (-5525 775);
PAINT SKYBLUE (-5525 775);
FORCEPROP 1 LASTPIN (-5475 775) $PN 2
J 2
(-5485 755);
DISPLAY 0.787234 (-5485 755);
PAINT ORANGE (-5485 755);
DISPLAY INVISIBLE (-5485 755);
FORCEPROP 1 LASTPIN (-5475 975) $PN 1
J 2
(-5485 955);
DISPLAY 0.787234 (-5485 955);
PAINT ORANGE (-5485 955);
DISPLAY INVISIBLE (-5485 955);
FORCEPROP 2 LAST CDS_LIB mstr_discrete
J 0
(-5475 875);
PAINT ORANGE (-5475 875);
DISPLAY INVISIBLE (-5475 875);
FORCEPROP 2 LAST CDS_LOCATION C3P11
J 2
(-5525 975);
DISPLAY 0.617021 (-5525 975);
PAINT AQUA (-5525 975);
DISPLAY INVISIBLE (-5525 975);
FORCEPROP 2 LAST CDS_SEC 1
J 0
(-5525 1075);
DISPLAY 1.021277 (-5525 1075);
PAINT ORANGE (-5525 1075);
DISPLAY INVISIBLE (-5525 1075);
FORCEPROP 2 LAST $SEC 1
J 0
(-5525 1075);
DISPLAY 0.680851 (-5525 1075);
PAINT MONO (-5525 1075);
DISPLAY INVISIBLE (-5525 1075);
FORCEPROP 1 LAST PATH I212
J 2
(-5525 1025);
DISPLAY 0.978723 (-5525 1025);
PAINT WHITE (-5525 1025);
DISPLAY INVISIBLE (-5525 1025);
FORCEADD TAP..7
(-5725 1325);
FORCEPROP 3 LASTPIN (-5725 1375) SIG_NAME P3E_CPU0_PE1_PCH_TXN<1>
J 0
(-5715 1385);
DISPLAY 0.659574 (-5715 1385);
PAINT MONO (-5715 1385);
DISPLAY INVISIBLE (-5715 1385);
FORCEPROP 1 LASTPIN (-5725 1375) BN 1
R 1
J 0
(-5732 1323);
DISPLAY 0.617021 (-5732 1323);
PAINT GREEN (-5732 1323);
FORCEPROP 2 LAST CDS_LIB mstr_standard
J 0
(-5725 1325);
PAINT ORANGE (-5725 1325);
DISPLAY INVISIBLE (-5725 1325);
FORCEPROP 1 LAST BODY_TYPE PLUMBING
J 0
(-5675 1325);
DISPLAY 2.276596 (-5675 1325);
PAINT GREEN (-5675 1325);
DISPLAY INVISIBLE (-5675 1325);
FORCEPROP 1 LAST PATH I213
J 0
(-5727 1325);
DISPLAY 0.872340 (-5727 1325);
PAINT GREEN (-5727 1325);
DISPLAY INVISIBLE (-5727 1325);
FORCEPROP 1 LAST HDL_TAP TRUE
J 0
(-5405 1195);
DISPLAY 2.276596 (-5405 1195);
PAINT GREEN (-5405 1195);
DISPLAY INVISIBLE (-5405 1195);
FORCEADD TAP..3
(-5675 1125);
FORCEPROP 3 LASTPIN (-5675 1075) SIG_NAME P3E_CPU0_PE1_SS_TXP<1>
J 0
(-5665 1085);
DISPLAY 0.659574 (-5665 1085);
PAINT MONO (-5665 1085);
DISPLAY INVISIBLE (-5665 1085);
FORCEPROP 1 LASTPIN (-5675 1075) BN 1
R 1
J 0
(-5682 1063);
DISPLAY 0.617021 (-5682 1063);
PAINT GREEN (-5682 1063);
FORCEPROP 1 LAST HDL_TAP TRUE
J 0
(-5355 995);
DISPLAY 2.276596 (-5355 995);
PAINT GREEN (-5355 995);
DISPLAY INVISIBLE (-5355 995);
FORCEPROP 1 LAST PATH I214
J 0
(-5677 1125);
DISPLAY 0.872340 (-5677 1125);
PAINT GREEN (-5677 1125);
DISPLAY INVISIBLE (-5677 1125);
FORCEPROP 2 LAST CDS_LIB mstr_standard
J 0
(-5675 1125);
PAINT ORANGE (-5675 1125);
DISPLAY INVISIBLE (-5675 1125);
FORCEPROP 1 LAST BODY_TYPE PLUMBING
J 0
(-5625 1075);
DISPLAY 2.276596 (-5625 1075);
PAINT GREEN (-5625 1075);
DISPLAY INVISIBLE (-5625 1075);
FORCEADD CAP..1
R 2
(-5925 1900);
FORCEPROP 1 LAST PART_NUMBER A36096-155
J 2
(-5975 1750);
DISPLAY 0.617021 (-5975 1750);
PAINT BLUE (-5975 1750);
FORCEPROP 1 LAST VALUE 0.22UF
J 2
(-5975 1950);
DISPLAY 0.617021 (-5975 1950);
PAINT SKYBLUE (-5975 1950);
FORCEPROP 1 LAST PACK_TYPE 0402
J 2
(-5975 1700);
DISPLAY 0.617021 (-5975 1700);
PAINT SKYBLUE (-5975 1700);
FORCEPROP 1 LAST MATERIAL X7R
J 2
(-5975 1800);
DISPLAY 0.617021 (-5975 1800);
PAINT SKYBLUE (-5975 1800);
FORCEPROP 1 LAST VOLTAGE 16V
J 2
(-5975 1900);
DISPLAY 0.617021 (-5975 1900);
PAINT SKYBLUE (-5975 1900);
FORCEPROP 1 LAST TOLERANCE 10%
J 2
(-5975 1850);
DISPLAY 0.617021 (-5975 1850);
PAINT SKYBLUE (-5975 1850);
FORCEPROP 1 LAST LOCATION C3P20
J 2
(-5975 2000);
DISPLAY 0.617021 (-5975 2000);
PAINT AQUA (-5975 2000);
FORCEPROP 1 LASTPIN (-5925 1800) $PN 2
J 2
(-5935 1780);
DISPLAY 0.787234 (-5935 1780);
PAINT ORANGE (-5935 1780);
DISPLAY INVISIBLE (-5935 1780);
FORCEPROP 1 LASTPIN (-5925 2000) $PN 1
J 2
(-5935 1980);
DISPLAY 0.787234 (-5935 1980);
PAINT ORANGE (-5935 1980);
DISPLAY INVISIBLE (-5935 1980);
FORCEPROP 2 LAST CDS_LOCATION C3P20
J 2
(-5975 2000);
DISPLAY 0.617021 (-5975 2000);
PAINT AQUA (-5975 2000);
DISPLAY INVISIBLE (-5975 2000);
FORCEPROP 2 LAST CDS_LIB mstr_discrete
J 0
(-5925 1900);
PAINT ORANGE (-5925 1900);
DISPLAY INVISIBLE (-5925 1900);
FORCEPROP 2 LAST CDS_SEC 1
J 0
(-5975 2100);
DISPLAY 1.021277 (-5975 2100);
PAINT ORANGE (-5975 2100);
DISPLAY INVISIBLE (-5975 2100);
FORCEPROP 2 LAST $SEC 1
J 0
(-5975 2100);
DISPLAY 0.680851 (-5975 2100);
PAINT MONO (-5975 2100);
DISPLAY INVISIBLE (-5975 2100);
FORCEPROP 1 LAST PATH I215
J 2
(-5975 2050);
DISPLAY 0.978723 (-5975 2050);
PAINT WHITE (-5975 2050);
DISPLAY INVISIBLE (-5975 2050);
FORCEADD CAP..1
R 2
(-6125 1575);
FORCEPROP 1 LAST PART_NUMBER A36096-155
J 2
(-6175 1425);
DISPLAY 0.617021 (-6175 1425);
PAINT BLUE (-6175 1425);
FORCEPROP 1 LAST PACK_TYPE 0402
J 2
(-6175 1375);
DISPLAY 0.617021 (-6175 1375);
PAINT SKYBLUE (-6175 1375);
FORCEPROP 1 LAST MATERIAL X7R
J 2
(-6175 1475);
DISPLAY 0.617021 (-6175 1475);
PAINT SKYBLUE (-6175 1475);
FORCEPROP 1 LAST TOLERANCE 10%
J 2
(-6175 1525);
DISPLAY 0.617021 (-6175 1525);
PAINT SKYBLUE (-6175 1525);
FORCEPROP 1 LAST VOLTAGE 16V
J 2
(-6175 1575);
DISPLAY 0.617021 (-6175 1575);
PAINT SKYBLUE (-6175 1575);
FORCEPROP 1 LAST VALUE 0.22UF
J 2
(-6175 1625);
DISPLAY 0.617021 (-6175 1625);
PAINT SKYBLUE (-6175 1625);
FORCEPROP 1 LAST LOCATION C3P25
J 2
(-6175 1675);
DISPLAY 0.617021 (-6175 1675);
PAINT AQUA (-6175 1675);
FORCEPROP 1 LAST PATH I216
J 2
(-6175 1725);
DISPLAY 0.978723 (-6175 1725);
PAINT WHITE (-6175 1725);
DISPLAY INVISIBLE (-6175 1725);
FORCEPROP 2 LAST CDS_LOCATION C3P25
J 2
(-6175 1675);
DISPLAY 0.617021 (-6175 1675);
PAINT AQUA (-6175 1675);
DISPLAY INVISIBLE (-6175 1675);
FORCEPROP 2 LAST $SEC 1
J 0
(-6175 1775);
DISPLAY 0.680851 (-6175 1775);
PAINT MONO (-6175 1775);
DISPLAY INVISIBLE (-6175 1775);
FORCEPROP 2 LAST CDS_SEC 1
J 0
(-6175 1775);
DISPLAY 1.021277 (-6175 1775);
PAINT ORANGE (-6175 1775);
DISPLAY INVISIBLE (-6175 1775);
FORCEPROP 1 LASTPIN (-6125 1475) $PN 2
J 2
(-6135 1455);
DISPLAY 0.787234 (-6135 1455);
PAINT ORANGE (-6135 1455);
DISPLAY INVISIBLE (-6135 1455);
FORCEPROP 1 LASTPIN (-6125 1675) $PN 1
J 2
(-6135 1655);
DISPLAY 0.787234 (-6135 1655);
PAINT ORANGE (-6135 1655);
DISPLAY INVISIBLE (-6135 1655);
FORCEPROP 2 LAST CDS_LIB mstr_discrete
J 0
(-6125 1575);
PAINT ORANGE (-6125 1575);
DISPLAY INVISIBLE (-6125 1575);
FORCEADD TAP..7
(-5925 1325);
FORCEPROP 3 LASTPIN (-5925 1375) SIG_NAME P3E_CPU0_PE1_PCH_TXN<2>
J 0
(-5915 1385);
DISPLAY 0.659574 (-5915 1385);
PAINT MONO (-5915 1385);
DISPLAY INVISIBLE (-5915 1385);
FORCEPROP 1 LASTPIN (-5925 1375) BN 2
R 1
J 0
(-5932 1323);
DISPLAY 0.617021 (-5932 1323);
PAINT GREEN (-5932 1323);
FORCEPROP 1 LAST PATH I217
J 0
(-5927 1325);
DISPLAY 0.872340 (-5927 1325);
PAINT GREEN (-5927 1325);
DISPLAY INVISIBLE (-5927 1325);
FORCEPROP 2 LAST CDS_LIB mstr_standard
J 0
(-5925 1325);
PAINT ORANGE (-5925 1325);
DISPLAY INVISIBLE (-5925 1325);
FORCEPROP 1 LAST BODY_TYPE PLUMBING
J 0
(-5875 1325);
DISPLAY 2.276596 (-5875 1325);
PAINT GREEN (-5875 1325);
DISPLAY INVISIBLE (-5875 1325);
FORCEPROP 1 LAST HDL_TAP TRUE
J 0
(-5605 1195);
DISPLAY 2.276596 (-5605 1195);
PAINT GREEN (-5605 1195);
DISPLAY INVISIBLE (-5605 1195);
FORCEADD TAP..3
(-5875 1125);
FORCEPROP 3 LASTPIN (-5875 1075) SIG_NAME P3E_CPU0_PE1_SS_TXP<2>
J 0
(-5865 1085);
DISPLAY 0.659574 (-5865 1085);
PAINT MONO (-5865 1085);
DISPLAY INVISIBLE (-5865 1085);
FORCEPROP 1 LASTPIN (-5875 1075) BN 2
R 1
J 0
(-5882 1063);
DISPLAY 0.617021 (-5882 1063);
PAINT GREEN (-5882 1063);
FORCEPROP 1 LAST HDL_TAP TRUE
J 0
(-5555 995);
DISPLAY 2.276596 (-5555 995);
PAINT GREEN (-5555 995);
DISPLAY INVISIBLE (-5555 995);
FORCEPROP 1 LAST PATH I218
J 0
(-5877 1125);
DISPLAY 0.872340 (-5877 1125);
PAINT GREEN (-5877 1125);
DISPLAY INVISIBLE (-5877 1125);
FORCEPROP 1 LAST BODY_TYPE PLUMBING
J 0
(-5825 1075);
DISPLAY 2.276596 (-5825 1075);
PAINT GREEN (-5825 1075);
DISPLAY INVISIBLE (-5825 1075);
FORCEPROP 2 LAST CDS_LIB mstr_standard
J 0
(-5875 1125);
PAINT ORANGE (-5875 1125);
DISPLAY INVISIBLE (-5875 1125);
FORCEADD CAP..1
R 2
(-5875 875);
FORCEPROP 1 LAST PART_NUMBER A36096-155
J 2
(-5925 725);
DISPLAY 0.617021 (-5925 725);
PAINT BLUE (-5925 725);
FORCEPROP 1 LAST PACK_TYPE 0402
J 2
(-5925 675);
DISPLAY 0.617021 (-5925 675);
PAINT SKYBLUE (-5925 675);
FORCEPROP 1 LAST MATERIAL X7R
J 2
(-5925 775);
DISPLAY 0.617021 (-5925 775);
PAINT SKYBLUE (-5925 775);
FORCEPROP 1 LAST VOLTAGE 16V
J 2
(-5925 875);
DISPLAY 0.617021 (-5925 875);
PAINT SKYBLUE (-5925 875);
FORCEPROP 1 LAST TOLERANCE 10%
J 2
(-5925 825);
DISPLAY 0.617021 (-5925 825);
PAINT SKYBLUE (-5925 825);
FORCEPROP 1 LAST VALUE 0.22UF
J 2
(-5925 925);
DISPLAY 0.617021 (-5925 925);
PAINT SKYBLUE (-5925 925);
FORCEPROP 1 LAST LOCATION C3P18
J 2
(-5925 975);
DISPLAY 0.617021 (-5925 975);
PAINT AQUA (-5925 975);
FORCEPROP 2 LAST CDS_LOCATION C3P18
J 2
(-5925 975);
DISPLAY 0.617021 (-5925 975);
PAINT AQUA (-5925 975);
DISPLAY INVISIBLE (-5925 975);
FORCEPROP 1 LASTPIN (-5875 775) $PN 2
J 2
(-5885 755);
DISPLAY 0.787234 (-5885 755);
PAINT ORANGE (-5885 755);
DISPLAY INVISIBLE (-5885 755);
FORCEPROP 1 LASTPIN (-5875 975) $PN 1
J 2
(-5885 955);
DISPLAY 0.787234 (-5885 955);
PAINT ORANGE (-5885 955);
DISPLAY INVISIBLE (-5885 955);
FORCEPROP 2 LAST CDS_LIB mstr_discrete
J 0
(-5875 875);
PAINT ORANGE (-5875 875);
DISPLAY INVISIBLE (-5875 875);
FORCEPROP 1 LAST PATH I219
J 2
(-5925 1025);
DISPLAY 0.978723 (-5925 1025);
PAINT WHITE (-5925 1025);
DISPLAY INVISIBLE (-5925 1025);
FORCEPROP 2 LAST $SEC 1
J 0
(-5925 1075);
DISPLAY 0.680851 (-5925 1075);
PAINT MONO (-5925 1075);
DISPLAY INVISIBLE (-5925 1075);
FORCEPROP 2 LAST CDS_SEC 1
J 0
(-5925 1075);
DISPLAY 1.021277 (-5925 1075);
PAINT ORANGE (-5925 1075);
DISPLAY INVISIBLE (-5925 1075);
FORCEADD TAP..3
(-6075 1125);
FORCEPROP 3 LASTPIN (-6075 1075) SIG_NAME P3E_CPU0_PE1_SS_TXP<3>
J 0
(-6065 1085);
DISPLAY 0.659574 (-6065 1085);
PAINT MONO (-6065 1085);
DISPLAY INVISIBLE (-6065 1085);
FORCEPROP 1 LASTPIN (-6075 1075) BN 3
R 1
J 0
(-6082 1063);
DISPLAY 0.617021 (-6082 1063);
PAINT GREEN (-6082 1063);
FORCEPROP 1 LAST HDL_TAP TRUE
J 0
(-5755 995);
DISPLAY 2.276596 (-5755 995);
PAINT GREEN (-5755 995);
DISPLAY INVISIBLE (-5755 995);
FORCEPROP 1 LAST PATH I220
J 0
(-6077 1125);
DISPLAY 0.872340 (-6077 1125);
PAINT GREEN (-6077 1125);
DISPLAY INVISIBLE (-6077 1125);
FORCEPROP 1 LAST BODY_TYPE PLUMBING
J 0
(-6025 1075);
DISPLAY 2.276596 (-6025 1075);
PAINT GREEN (-6025 1075);
DISPLAY INVISIBLE (-6025 1075);
FORCEPROP 2 LAST CDS_LIB mstr_standard
J 0
(-6075 1125);
PAINT ORANGE (-6075 1125);
DISPLAY INVISIBLE (-6075 1125);
FORCEADD TAP..7
(-6125 1325);
FORCEPROP 3 LASTPIN (-6125 1375) SIG_NAME P3E_CPU0_PE1_PCH_TXN<3>
J 0
(-6115 1385);
DISPLAY 0.659574 (-6115 1385);
PAINT MONO (-6115 1385);
DISPLAY INVISIBLE (-6115 1385);
FORCEPROP 1 LASTPIN (-6125 1375) BN 3
R 1
J 0
(-6132 1323);
DISPLAY 0.617021 (-6132 1323);
PAINT GREEN (-6132 1323);
FORCEPROP 1 LAST PATH I221
J 0
(-6127 1325);
DISPLAY 0.872340 (-6127 1325);
PAINT GREEN (-6127 1325);
DISPLAY INVISIBLE (-6127 1325);
FORCEPROP 1 LAST BODY_TYPE PLUMBING
J 0
(-6075 1325);
DISPLAY 2.276596 (-6075 1325);
PAINT GREEN (-6075 1325);
DISPLAY INVISIBLE (-6075 1325);
FORCEPROP 2 LAST CDS_LIB mstr_standard
J 0
(-6125 1325);
PAINT ORANGE (-6125 1325);
DISPLAY INVISIBLE (-6125 1325);
FORCEPROP 1 LAST HDL_TAP TRUE
J 0
(-5805 1195);
DISPLAY 2.276596 (-5805 1195);
PAINT GREEN (-5805 1195);
DISPLAY INVISIBLE (-5805 1195);
FORCEADD TAP..3
(-6275 1125);
FORCEPROP 3 LASTPIN (-6275 1075) SIG_NAME P3E_CPU0_PE1_SS_TXP<4>
J 0
(-6265 1085);
DISPLAY 0.659574 (-6265 1085);
PAINT MONO (-6265 1085);
DISPLAY INVISIBLE (-6265 1085);
FORCEPROP 1 LASTPIN (-6275 1075) BN 4
R 1
J 0
(-6282 1063);
DISPLAY 0.617021 (-6282 1063);
PAINT GREEN (-6282 1063);
FORCEPROP 2 LAST CDS_LIB mstr_standard
J 0
(-6275 1125);
PAINT ORANGE (-6275 1125);
DISPLAY INVISIBLE (-6275 1125);
FORCEPROP 1 LAST PATH I222
J 0
(-6277 1125);
DISPLAY 0.872340 (-6277 1125);
PAINT GREEN (-6277 1125);
DISPLAY INVISIBLE (-6277 1125);
FORCEPROP 1 LAST BODY_TYPE PLUMBING
J 0
(-6225 1075);
DISPLAY 2.276596 (-6225 1075);
PAINT GREEN (-6225 1075);
DISPLAY INVISIBLE (-6225 1075);
FORCEPROP 1 LAST HDL_TAP TRUE
J 0
(-5955 995);
DISPLAY 2.276596 (-5955 995);
PAINT GREEN (-5955 995);
DISPLAY INVISIBLE (-5955 995);
FORCEADD CAP..1
R 2
(-6275 875);
FORCEPROP 1 LAST LOCATION C3P27
J 2
(-6325 975);
DISPLAY 0.617021 (-6325 975);
PAINT AQUA (-6325 975);
FORCEPROP 1 LAST PART_NUMBER A36096-155
J 2
(-6325 725);
DISPLAY 0.617021 (-6325 725);
PAINT BLUE (-6325 725);
FORCEPROP 1 LAST VALUE 0.22UF
J 2
(-6325 925);
DISPLAY 0.617021 (-6325 925);
PAINT SKYBLUE (-6325 925);
FORCEPROP 1 LAST TOLERANCE 10%
J 2
(-6325 825);
DISPLAY 0.617021 (-6325 825);
PAINT SKYBLUE (-6325 825);
FORCEPROP 1 LAST PACK_TYPE 0402
J 2
(-6325 675);
DISPLAY 0.617021 (-6325 675);
PAINT SKYBLUE (-6325 675);
FORCEPROP 1 LAST VOLTAGE 16V
J 2
(-6325 875);
DISPLAY 0.617021 (-6325 875);
PAINT SKYBLUE (-6325 875);
FORCEPROP 1 LAST MATERIAL X7R
J 2
(-6325 775);
DISPLAY 0.617021 (-6325 775);
PAINT SKYBLUE (-6325 775);
FORCEPROP 1 LASTPIN (-6275 775) $PN 2
J 2
(-6285 755);
DISPLAY 0.787234 (-6285 755);
PAINT ORANGE (-6285 755);
DISPLAY INVISIBLE (-6285 755);
FORCEPROP 1 LASTPIN (-6275 975) $PN 1
J 2
(-6285 955);
DISPLAY 0.787234 (-6285 955);
PAINT ORANGE (-6285 955);
DISPLAY INVISIBLE (-6285 955);
FORCEPROP 2 LAST CDS_LIB mstr_discrete
J 0
(-6275 875);
PAINT ORANGE (-6275 875);
DISPLAY INVISIBLE (-6275 875);
FORCEPROP 2 LAST CDS_LOCATION C3P27
J 2
(-6325 975);
DISPLAY 0.617021 (-6325 975);
PAINT AQUA (-6325 975);
DISPLAY INVISIBLE (-6325 975);
FORCEPROP 2 LAST CDS_SEC 1
J 0
(-6325 1075);
DISPLAY 1.021277 (-6325 1075);
PAINT ORANGE (-6325 1075);
DISPLAY INVISIBLE (-6325 1075);
FORCEPROP 2 LAST $SEC 1
J 0
(-6325 1075);
DISPLAY 0.680851 (-6325 1075);
PAINT MONO (-6325 1075);
DISPLAY INVISIBLE (-6325 1075);
FORCEPROP 1 LAST PATH I223
J 2
(-6325 1025);
DISPLAY 0.978723 (-6325 1025);
PAINT WHITE (-6325 1025);
DISPLAY INVISIBLE (-6325 1025);
FORCEADD TAP..7
(-5475 325);
FORCEPROP 3 LASTPIN (-5475 375) SIG_NAME P3E_CPU0_PE1_PCH_TXP<0>
J 0
(-5465 385);
DISPLAY 0.659574 (-5465 385);
PAINT MONO (-5465 385);
DISPLAY INVISIBLE (-5465 385);
FORCEPROP 1 LASTPIN (-5475 375) BN 0
R 1
J 0
(-5482 323);
DISPLAY 0.617021 (-5482 323);
PAINT GREEN (-5482 323);
FORCEPROP 2 LAST CDS_LIB mstr_standard
J 0
(-5475 325);
PAINT ORANGE (-5475 325);
DISPLAY INVISIBLE (-5475 325);
FORCEPROP 1 LAST BODY_TYPE PLUMBING
J 0
(-5425 325);
DISPLAY 2.276596 (-5425 325);
PAINT GREEN (-5425 325);
DISPLAY INVISIBLE (-5425 325);
FORCEPROP 1 LAST PATH I224
J 0
(-5477 325);
DISPLAY 0.872340 (-5477 325);
PAINT GREEN (-5477 325);
DISPLAY INVISIBLE (-5477 325);
FORCEPROP 1 LAST HDL_TAP TRUE
J 0
(-5155 195);
DISPLAY 2.276596 (-5155 195);
PAINT GREEN (-5155 195);
DISPLAY INVISIBLE (-5155 195);
FORCEADD OFFPAGE..2
(-5250 275);
FORCEPROP 2 LAST $XR0 117 
J 0
(-5061 275);
DISPLAY 0.638298 (-5061 275);
PAINT MONO (-5061 275);
FORCEPROP 1 LAST COMMENT_BODY TRUE
J 0
(-5295 180);
DISPLAY 0.872340 (-5295 180);
PAINT GREEN (-5295 180);
DISPLAY INVISIBLE (-5295 180);
FORCEPROP 2 LAST CDS_LIB mstr_standard
J 0
(-5250 275);
PAINT ORANGE (-5250 275);
DISPLAY INVISIBLE (-5250 275);
FORCEPROP 2 LAST PATH I225
J 0
(-5075 350);
DISPLAY 1.021277 (-5075 350);
PAINT ORANGE (-5075 350);
DISPLAY INVISIBLE (-5075 350);
FORCEPROP 1 LAST OFFPAGE TRUE
J 0
(-4925 150);
DISPLAY 0.872340 (-4925 150);
PAINT GREEN (-4925 150);
DISPLAY INVISIBLE (-4925 150);
FORCEADD CAP..1
R 2
(-5675 575);
FORCEPROP 1 LAST PART_NUMBER A36096-155
J 2
(-5725 425);
DISPLAY 0.617021 (-5725 425);
PAINT BLUE (-5725 425);
FORCEPROP 1 LAST PACK_TYPE 0402
J 2
(-5725 375);
DISPLAY 0.617021 (-5725 375);
PAINT SKYBLUE (-5725 375);
FORCEPROP 1 LAST MATERIAL X7R
J 2
(-5725 475);
DISPLAY 0.617021 (-5725 475);
PAINT SKYBLUE (-5725 475);
FORCEPROP 1 LAST VALUE 0.22UF
J 2
(-5725 625);
DISPLAY 0.617021 (-5725 625);
PAINT SKYBLUE (-5725 625);
FORCEPROP 1 LAST VOLTAGE 16V
J 2
(-5725 575);
DISPLAY 0.617021 (-5725 575);
PAINT SKYBLUE (-5725 575);
FORCEPROP 1 LAST TOLERANCE 10%
J 2
(-5725 525);
DISPLAY 0.617021 (-5725 525);
PAINT SKYBLUE (-5725 525);
FORCEPROP 1 LAST LOCATION C3P15
J 2
(-5725 675);
DISPLAY 0.617021 (-5725 675);
PAINT AQUA (-5725 675);
FORCEPROP 1 LASTPIN (-5675 475) $PN 2
J 2
(-5685 455);
DISPLAY 0.787234 (-5685 455);
PAINT ORANGE (-5685 455);
DISPLAY INVISIBLE (-5685 455);
FORCEPROP 1 LAST PATH I226
J 2
(-5725 725);
DISPLAY 0.978723 (-5725 725);
PAINT WHITE (-5725 725);
DISPLAY INVISIBLE (-5725 725);
FORCEPROP 1 LASTPIN (-5675 675) $PN 1
J 2
(-5685 655);
DISPLAY 0.787234 (-5685 655);
PAINT ORANGE (-5685 655);
DISPLAY INVISIBLE (-5685 655);
FORCEPROP 2 LAST CDS_LIB mstr_discrete
J 0
(-5675 575);
PAINT ORANGE (-5675 575);
DISPLAY INVISIBLE (-5675 575);
FORCEPROP 2 LAST CDS_LOCATION C3P15
J 2
(-5725 675);
DISPLAY 0.617021 (-5725 675);
PAINT AQUA (-5725 675);
DISPLAY INVISIBLE (-5725 675);
FORCEPROP 2 LAST $SEC 1
J 0
(-5725 775);
DISPLAY 0.680851 (-5725 775);
PAINT MONO (-5725 775);
DISPLAY INVISIBLE (-5725 775);
FORCEPROP 2 LAST CDS_SEC 1
J 0
(-5725 775);
DISPLAY 1.021277 (-5725 775);
PAINT ORANGE (-5725 775);
DISPLAY INVISIBLE (-5725 775);
FORCEADD TAP..7
(-5675 325);
FORCEPROP 3 LASTPIN (-5675 375) SIG_NAME P3E_CPU0_PE1_PCH_TXP<1>
J 0
(-5665 385);
DISPLAY 0.659574 (-5665 385);
PAINT MONO (-5665 385);
DISPLAY INVISIBLE (-5665 385);
FORCEPROP 1 LASTPIN (-5675 375) BN 1
R 1
J 0
(-5682 323);
DISPLAY 0.617021 (-5682 323);
PAINT GREEN (-5682 323);
FORCEPROP 1 LAST PATH I227
J 0
(-5677 325);
DISPLAY 0.872340 (-5677 325);
PAINT GREEN (-5677 325);
DISPLAY INVISIBLE (-5677 325);
FORCEPROP 2 LAST CDS_LIB mstr_standard
J 0
(-5675 325);
PAINT ORANGE (-5675 325);
DISPLAY INVISIBLE (-5675 325);
FORCEPROP 1 LAST BODY_TYPE PLUMBING
J 0
(-5625 325);
DISPLAY 2.276596 (-5625 325);
PAINT GREEN (-5625 325);
DISPLAY INVISIBLE (-5625 325);
FORCEPROP 1 LAST HDL_TAP TRUE
J 0
(-5355 195);
DISPLAY 2.276596 (-5355 195);
PAINT GREEN (-5355 195);
DISPLAY INVISIBLE (-5355 195);
FORCEADD TAP..7
(-5875 325);
FORCEPROP 3 LASTPIN (-5875 375) SIG_NAME P3E_CPU0_PE1_PCH_TXP<2>
J 0
(-5865 385);
DISPLAY 0.659574 (-5865 385);
PAINT MONO (-5865 385);
DISPLAY INVISIBLE (-5865 385);
FORCEPROP 1 LASTPIN (-5875 375) BN 2
R 1
J 0
(-5882 323);
DISPLAY 0.617021 (-5882 323);
PAINT GREEN (-5882 323);
FORCEPROP 1 LAST PATH I228
J 0
(-5877 325);
DISPLAY 0.872340 (-5877 325);
PAINT GREEN (-5877 325);
DISPLAY INVISIBLE (-5877 325);
FORCEPROP 2 LAST CDS_LIB mstr_standard
J 0
(-5875 325);
PAINT ORANGE (-5875 325);
DISPLAY INVISIBLE (-5875 325);
FORCEPROP 1 LAST BODY_TYPE PLUMBING
J 0
(-5825 325);
DISPLAY 2.276596 (-5825 325);
PAINT GREEN (-5825 325);
DISPLAY INVISIBLE (-5825 325);
FORCEPROP 1 LAST HDL_TAP TRUE
J 0
(-5555 195);
DISPLAY 2.276596 (-5555 195);
PAINT GREEN (-5555 195);
DISPLAY INVISIBLE (-5555 195);
FORCEADD CAP..1
R 2
(-6075 575);
FORCEPROP 1 LAST LOCATION C3P23
J 2
(-6125 675);
DISPLAY 0.617021 (-6125 675);
PAINT AQUA (-6125 675);
FORCEPROP 1 LAST PART_NUMBER A36096-155
J 2
(-6125 425);
DISPLAY 0.617021 (-6125 425);
PAINT BLUE (-6125 425);
FORCEPROP 1 LAST VALUE 0.22UF
J 2
(-6125 625);
DISPLAY 0.617021 (-6125 625);
PAINT SKYBLUE (-6125 625);
FORCEPROP 1 LAST TOLERANCE 10%
J 2
(-6125 525);
DISPLAY 0.617021 (-6125 525);
PAINT SKYBLUE (-6125 525);
FORCEPROP 1 LAST PACK_TYPE 0402
J 2
(-6125 375);
DISPLAY 0.617021 (-6125 375);
PAINT SKYBLUE (-6125 375);
FORCEPROP 1 LAST VOLTAGE 16V
J 2
(-6125 575);
DISPLAY 0.617021 (-6125 575);
PAINT SKYBLUE (-6125 575);
FORCEPROP 1 LAST MATERIAL X7R
J 2
(-6125 475);
DISPLAY 0.617021 (-6125 475);
PAINT SKYBLUE (-6125 475);
FORCEPROP 1 LASTPIN (-6075 475) $PN 2
J 2
(-6085 455);
DISPLAY 0.787234 (-6085 455);
PAINT ORANGE (-6085 455);
DISPLAY INVISIBLE (-6085 455);
FORCEPROP 1 LAST PATH I229
J 2
(-6125 725);
DISPLAY 0.978723 (-6125 725);
PAINT WHITE (-6125 725);
DISPLAY INVISIBLE (-6125 725);
FORCEPROP 2 LAST CDS_LOCATION C3P23
J 2
(-6125 675);
DISPLAY 0.617021 (-6125 675);
PAINT AQUA (-6125 675);
DISPLAY INVISIBLE (-6125 675);
FORCEPROP 2 LAST CDS_LIB mstr_discrete
J 0
(-6075 575);
PAINT ORANGE (-6075 575);
DISPLAY INVISIBLE (-6075 575);
FORCEPROP 1 LASTPIN (-6075 675) $PN 1
J 2
(-6085 655);
DISPLAY 0.787234 (-6085 655);
PAINT ORANGE (-6085 655);
DISPLAY INVISIBLE (-6085 655);
FORCEPROP 2 LAST $SEC 1
J 0
(-6125 775);
DISPLAY 0.680851 (-6125 775);
PAINT MONO (-6125 775);
DISPLAY INVISIBLE (-6125 775);
FORCEPROP 2 LAST CDS_SEC 1
J 0
(-6125 775);
DISPLAY 1.021277 (-6125 775);
PAINT ORANGE (-6125 775);
DISPLAY INVISIBLE (-6125 775);
FORCEADD TAP..7
(-6075 325);
FORCEPROP 3 LASTPIN (-6075 375) SIG_NAME P3E_CPU0_PE1_PCH_TXP<3>
J 0
(-6065 385);
DISPLAY 0.659574 (-6065 385);
PAINT MONO (-6065 385);
DISPLAY INVISIBLE (-6065 385);
FORCEPROP 1 LASTPIN (-6075 375) BN 3
R 1
J 0
(-6082 323);
DISPLAY 0.617021 (-6082 323);
PAINT GREEN (-6082 323);
FORCEPROP 1 LAST PATH I230
J 0
(-6077 325);
DISPLAY 0.872340 (-6077 325);
PAINT GREEN (-6077 325);
DISPLAY INVISIBLE (-6077 325);
FORCEPROP 2 LAST CDS_LIB mstr_standard
J 0
(-6075 325);
PAINT ORANGE (-6075 325);
DISPLAY INVISIBLE (-6075 325);
FORCEPROP 1 LAST BODY_TYPE PLUMBING
J 0
(-6025 325);
DISPLAY 2.276596 (-6025 325);
PAINT GREEN (-6025 325);
DISPLAY INVISIBLE (-6025 325);
FORCEPROP 1 LAST HDL_TAP TRUE
J 0
(-5755 195);
DISPLAY 2.276596 (-5755 195);
PAINT GREEN (-5755 195);
DISPLAY INVISIBLE (-5755 195);
FORCEADD TAP..7
(-6275 325);
FORCEPROP 3 LASTPIN (-6275 375) SIG_NAME P3E_CPU0_PE1_PCH_TXP<4>
J 0
(-6265 385);
DISPLAY 0.659574 (-6265 385);
PAINT MONO (-6265 385);
DISPLAY INVISIBLE (-6265 385);
FORCEPROP 1 LASTPIN (-6275 375) BN 4
R 1
J 0
(-6282 323);
DISPLAY 0.617021 (-6282 323);
PAINT GREEN (-6282 323);
FORCEPROP 2 LAST CDS_LIB mstr_standard
J 0
(-6275 325);
PAINT ORANGE (-6275 325);
DISPLAY INVISIBLE (-6275 325);
FORCEPROP 1 LAST BODY_TYPE PLUMBING
J 0
(-6225 325);
DISPLAY 2.276596 (-6225 325);
PAINT GREEN (-6225 325);
DISPLAY INVISIBLE (-6225 325);
FORCEPROP 1 LAST PATH I231
J 0
(-6277 325);
DISPLAY 0.872340 (-6277 325);
PAINT GREEN (-6277 325);
DISPLAY INVISIBLE (-6277 325);
FORCEPROP 1 LAST HDL_TAP TRUE
J 0
(-5955 195);
DISPLAY 2.276596 (-5955 195);
PAINT GREEN (-5955 195);
DISPLAY INVISIBLE (-5955 195);
FORCEADD CAP..1
R 2
(-6325 1875);
FORCEPROP 1 LAST PART_NUMBER A36096-155
J 2
(-6375 1725);
DISPLAY 0.617021 (-6375 1725);
PAINT BLUE (-6375 1725);
FORCEPROP 1 LAST LOCATION C3P28
J 2
(-6375 1975);
DISPLAY 0.617021 (-6375 1975);
PAINT AQUA (-6375 1975);
FORCEPROP 1 LAST VALUE 0.22UF
J 2
(-6375 1925);
DISPLAY 0.617021 (-6375 1925);
PAINT SKYBLUE (-6375 1925);
FORCEPROP 1 LAST TOLERANCE 10%
J 2
(-6375 1825);
DISPLAY 0.617021 (-6375 1825);
PAINT SKYBLUE (-6375 1825);
FORCEPROP 1 LAST PACK_TYPE 0402
J 2
(-6375 1675);
DISPLAY 0.617021 (-6375 1675);
PAINT SKYBLUE (-6375 1675);
FORCEPROP 1 LAST VOLTAGE 16V
J 2
(-6375 1875);
DISPLAY 0.617021 (-6375 1875);
PAINT SKYBLUE (-6375 1875);
FORCEPROP 1 LAST MATERIAL X7R
J 2
(-6375 1775);
DISPLAY 0.617021 (-6375 1775);
PAINT SKYBLUE (-6375 1775);
FORCEPROP 1 LASTPIN (-6325 1775) $PN 2
J 2
(-6335 1755);
DISPLAY 0.787234 (-6335 1755);
PAINT ORANGE (-6335 1755);
DISPLAY INVISIBLE (-6335 1755);
FORCEPROP 2 LAST CDS_LOCATION C3P28
J 2
(-6375 1975);
DISPLAY 0.617021 (-6375 1975);
PAINT AQUA (-6375 1975);
DISPLAY INVISIBLE (-6375 1975);
FORCEPROP 2 LAST CDS_LIB mstr_discrete
J 0
(-6325 1875);
PAINT ORANGE (-6325 1875);
DISPLAY INVISIBLE (-6325 1875);
FORCEPROP 1 LASTPIN (-6325 1975) $PN 1
J 2
(-6335 1955);
DISPLAY 0.787234 (-6335 1955);
PAINT ORANGE (-6335 1955);
DISPLAY INVISIBLE (-6335 1955);
FORCEPROP 1 LAST PATH I232
J 2
(-6375 2025);
DISPLAY 0.978723 (-6375 2025);
PAINT WHITE (-6375 2025);
DISPLAY INVISIBLE (-6375 2025);
FORCEPROP 2 LAST CDS_SEC 1
J 0
(-6375 2075);
DISPLAY 1.021277 (-6375 2075);
PAINT ORANGE (-6375 2075);
DISPLAY INVISIBLE (-6375 2075);
FORCEPROP 2 LAST $SEC 1
J 0
(-6375 2075);
DISPLAY 0.680851 (-6375 2075);
PAINT MONO (-6375 2075);
DISPLAY INVISIBLE (-6375 2075);
FORCEADD TAP..7
(-6325 1325);
FORCEPROP 3 LASTPIN (-6325 1375) SIG_NAME P3E_CPU0_PE1_PCH_TXN<4>
J 0
(-6315 1385);
DISPLAY 0.659574 (-6315 1385);
PAINT MONO (-6315 1385);
DISPLAY INVISIBLE (-6315 1385);
FORCEPROP 1 LASTPIN (-6325 1375) BN 4
R 1
J 0
(-6332 1323);
DISPLAY 0.617021 (-6332 1323);
PAINT GREEN (-6332 1323);
FORCEPROP 1 LAST PATH I233
J 0
(-6327 1325);
DISPLAY 0.872340 (-6327 1325);
PAINT GREEN (-6327 1325);
DISPLAY INVISIBLE (-6327 1325);
FORCEPROP 1 LAST BODY_TYPE PLUMBING
J 0
(-6275 1325);
DISPLAY 2.276596 (-6275 1325);
PAINT GREEN (-6275 1325);
DISPLAY INVISIBLE (-6275 1325);
FORCEPROP 2 LAST CDS_LIB mstr_standard
J 0
(-6325 1325);
PAINT ORANGE (-6325 1325);
DISPLAY INVISIBLE (-6325 1325);
FORCEPROP 1 LAST HDL_TAP TRUE
J 0
(-6005 1195);
DISPLAY 2.276596 (-6005 1195);
PAINT GREEN (-6005 1195);
DISPLAY INVISIBLE (-6005 1195);
FORCEADD CAP..1
R 2
(-6525 1575);
FORCEPROP 1 LAST LOCATION C3P32
J 2
(-6575 1675);
DISPLAY 0.617021 (-6575 1675);
PAINT AQUA (-6575 1675);
FORCEPROP 1 LAST PART_NUMBER A36096-155
J 2
(-6575 1425);
DISPLAY 0.617021 (-6575 1425);
PAINT BLUE (-6575 1425);
FORCEPROP 1 LAST VALUE 0.22UF
J 2
(-6575 1625);
DISPLAY 0.617021 (-6575 1625);
PAINT SKYBLUE (-6575 1625);
FORCEPROP 1 LAST TOLERANCE 10%
J 2
(-6575 1525);
DISPLAY 0.617021 (-6575 1525);
PAINT SKYBLUE (-6575 1525);
FORCEPROP 1 LAST PACK_TYPE 0402
J 2
(-6575 1375);
DISPLAY 0.617021 (-6575 1375);
PAINT SKYBLUE (-6575 1375);
FORCEPROP 1 LAST VOLTAGE 16V
J 2
(-6575 1575);
DISPLAY 0.617021 (-6575 1575);
PAINT SKYBLUE (-6575 1575);
FORCEPROP 1 LAST MATERIAL X7R
J 2
(-6575 1475);
DISPLAY 0.617021 (-6575 1475);
PAINT SKYBLUE (-6575 1475);
FORCEPROP 1 LASTPIN (-6525 1475) $PN 2
J 2
(-6535 1455);
DISPLAY 0.787234 (-6535 1455);
PAINT ORANGE (-6535 1455);
DISPLAY INVISIBLE (-6535 1455);
FORCEPROP 2 LAST $SEC 1
J 0
(-6575 1775);
DISPLAY 0.680851 (-6575 1775);
PAINT MONO (-6575 1775);
DISPLAY INVISIBLE (-6575 1775);
FORCEPROP 2 LAST CDS_SEC 1
J 0
(-6575 1775);
DISPLAY 1.021277 (-6575 1775);
PAINT ORANGE (-6575 1775);
DISPLAY INVISIBLE (-6575 1775);
FORCEPROP 2 LAST CDS_LIB mstr_discrete
J 0
(-6525 1575);
PAINT ORANGE (-6525 1575);
DISPLAY INVISIBLE (-6525 1575);
FORCEPROP 1 LAST PATH I234
J 2
(-6575 1725);
DISPLAY 0.978723 (-6575 1725);
PAINT WHITE (-6575 1725);
DISPLAY INVISIBLE (-6575 1725);
FORCEPROP 1 LASTPIN (-6525 1675) $PN 1
J 2
(-6535 1655);
DISPLAY 0.787234 (-6535 1655);
PAINT ORANGE (-6535 1655);
DISPLAY INVISIBLE (-6535 1655);
FORCEPROP 2 LAST CDS_LOCATION C3P32
J 2
(-6575 1675);
DISPLAY 0.617021 (-6575 1675);
PAINT AQUA (-6575 1675);
DISPLAY INVISIBLE (-6575 1675);
FORCEADD CAP..1
R 2
(-6725 1875);
FORCEPROP 1 LAST LOCATION C3P37
J 2
(-6775 1975);
DISPLAY 0.617021 (-6775 1975);
PAINT AQUA (-6775 1975);
FORCEPROP 1 LAST PART_NUMBER A36096-155
J 2
(-6775 1725);
DISPLAY 0.617021 (-6775 1725);
PAINT BLUE (-6775 1725);
FORCEPROP 1 LAST VALUE 0.22UF
J 2
(-6775 1925);
DISPLAY 0.617021 (-6775 1925);
PAINT SKYBLUE (-6775 1925);
FORCEPROP 1 LAST PACK_TYPE 0402
J 2
(-6775 1675);
DISPLAY 0.617021 (-6775 1675);
PAINT SKYBLUE (-6775 1675);
FORCEPROP 1 LAST MATERIAL X7R
J 2
(-6775 1775);
DISPLAY 0.617021 (-6775 1775);
PAINT SKYBLUE (-6775 1775);
FORCEPROP 1 LAST VOLTAGE 16V
J 2
(-6775 1875);
DISPLAY 0.617021 (-6775 1875);
PAINT SKYBLUE (-6775 1875);
FORCEPROP 1 LAST TOLERANCE 10%
J 2
(-6775 1825);
DISPLAY 0.617021 (-6775 1825);
PAINT SKYBLUE (-6775 1825);
FORCEPROP 1 LASTPIN (-6725 1775) $PN 2
J 2
(-6735 1755);
DISPLAY 0.787234 (-6735 1755);
PAINT ORANGE (-6735 1755);
DISPLAY INVISIBLE (-6735 1755);
FORCEPROP 2 LAST CDS_LOCATION C3P37
J 2
(-6775 1975);
DISPLAY 0.617021 (-6775 1975);
PAINT AQUA (-6775 1975);
DISPLAY INVISIBLE (-6775 1975);
FORCEPROP 2 LAST CDS_LIB mstr_discrete
J 0
(-6725 1875);
PAINT ORANGE (-6725 1875);
DISPLAY INVISIBLE (-6725 1875);
FORCEPROP 1 LASTPIN (-6725 1975) $PN 1
J 2
(-6735 1955);
DISPLAY 0.787234 (-6735 1955);
PAINT ORANGE (-6735 1955);
DISPLAY INVISIBLE (-6735 1955);
FORCEPROP 1 LAST PATH I235
J 2
(-6775 2025);
DISPLAY 0.978723 (-6775 2025);
PAINT WHITE (-6775 2025);
DISPLAY INVISIBLE (-6775 2025);
FORCEPROP 2 LAST CDS_SEC 1
J 0
(-6775 2075);
DISPLAY 1.021277 (-6775 2075);
PAINT ORANGE (-6775 2075);
DISPLAY INVISIBLE (-6775 2075);
FORCEPROP 2 LAST $SEC 1
J 0
(-6775 2075);
DISPLAY 0.680851 (-6775 2075);
PAINT MONO (-6775 2075);
DISPLAY INVISIBLE (-6775 2075);
FORCEADD TAP..7
(-6525 1325);
FORCEPROP 3 LASTPIN (-6525 1375) SIG_NAME P3E_CPU0_PE1_PCH_TXN<5>
J 0
(-6515 1385);
DISPLAY 0.659574 (-6515 1385);
PAINT MONO (-6515 1385);
DISPLAY INVISIBLE (-6515 1385);
FORCEPROP 1 LASTPIN (-6525 1375) BN 5
R 1
J 0
(-6532 1323);
DISPLAY 0.617021 (-6532 1323);
PAINT GREEN (-6532 1323);
FORCEPROP 2 LAST CDS_LIB mstr_standard
J 0
(-6525 1325);
PAINT ORANGE (-6525 1325);
DISPLAY INVISIBLE (-6525 1325);
FORCEPROP 1 LAST BODY_TYPE PLUMBING
J 0
(-6475 1325);
DISPLAY 2.276596 (-6475 1325);
PAINT GREEN (-6475 1325);
DISPLAY INVISIBLE (-6475 1325);
FORCEPROP 1 LAST PATH I236
J 0
(-6527 1325);
DISPLAY 0.872340 (-6527 1325);
PAINT GREEN (-6527 1325);
DISPLAY INVISIBLE (-6527 1325);
FORCEPROP 1 LAST HDL_TAP TRUE
J 0
(-6205 1195);
DISPLAY 2.276596 (-6205 1195);
PAINT GREEN (-6205 1195);
DISPLAY INVISIBLE (-6205 1195);
FORCEADD TAP..3
(-6475 1125);
FORCEPROP 3 LASTPIN (-6475 1075) SIG_NAME P3E_CPU0_PE1_SS_TXP<5>
J 0
(-6465 1085);
DISPLAY 0.659574 (-6465 1085);
PAINT MONO (-6465 1085);
DISPLAY INVISIBLE (-6465 1085);
FORCEPROP 1 LASTPIN (-6475 1075) BN 5
R 1
J 0
(-6482 1063);
DISPLAY 0.617021 (-6482 1063);
PAINT GREEN (-6482 1063);
FORCEPROP 1 LAST HDL_TAP TRUE
J 0
(-6155 995);
DISPLAY 2.276596 (-6155 995);
PAINT GREEN (-6155 995);
DISPLAY INVISIBLE (-6155 995);
FORCEPROP 1 LAST PATH I237
J 0
(-6477 1125);
DISPLAY 0.872340 (-6477 1125);
PAINT GREEN (-6477 1125);
DISPLAY INVISIBLE (-6477 1125);
FORCEPROP 1 LAST BODY_TYPE PLUMBING
J 0
(-6425 1075);
DISPLAY 2.276596 (-6425 1075);
PAINT GREEN (-6425 1075);
DISPLAY INVISIBLE (-6425 1075);
FORCEPROP 2 LAST CDS_LIB mstr_standard
J 0
(-6475 1125);
PAINT ORANGE (-6475 1125);
DISPLAY INVISIBLE (-6475 1125);
FORCEADD TAP..3
(-6675 1125);
FORCEPROP 3 LASTPIN (-6675 1075) SIG_NAME P3E_CPU0_PE1_SS_TXP<6>
J 0
(-6665 1085);
DISPLAY 0.659574 (-6665 1085);
PAINT MONO (-6665 1085);
DISPLAY INVISIBLE (-6665 1085);
FORCEPROP 1 LASTPIN (-6675 1075) BN 6
R 1
J 0
(-6682 1063);
DISPLAY 0.617021 (-6682 1063);
PAINT GREEN (-6682 1063);
FORCEPROP 1 LAST HDL_TAP TRUE
J 0
(-6355 995);
DISPLAY 2.276596 (-6355 995);
PAINT GREEN (-6355 995);
DISPLAY INVISIBLE (-6355 995);
FORCEPROP 1 LAST PATH I238
J 0
(-6677 1125);
DISPLAY 0.872340 (-6677 1125);
PAINT GREEN (-6677 1125);
DISPLAY INVISIBLE (-6677 1125);
FORCEPROP 2 LAST CDS_LIB mstr_standard
J 0
(-6675 1125);
PAINT ORANGE (-6675 1125);
DISPLAY INVISIBLE (-6675 1125);
FORCEPROP 1 LAST BODY_TYPE PLUMBING
J 0
(-6625 1075);
DISPLAY 2.276596 (-6625 1075);
PAINT GREEN (-6625 1075);
DISPLAY INVISIBLE (-6625 1075);
FORCEADD TAP..7
(-6725 1325);
FORCEPROP 3 LASTPIN (-6725 1375) SIG_NAME P3E_CPU0_PE1_PCH_TXN<6>
J 0
(-6715 1385);
DISPLAY 0.659574 (-6715 1385);
PAINT MONO (-6715 1385);
DISPLAY INVISIBLE (-6715 1385);
FORCEPROP 1 LASTPIN (-6725 1375) BN 6
R 1
J 0
(-6732 1323);
DISPLAY 0.617021 (-6732 1323);
PAINT GREEN (-6732 1323);
FORCEPROP 2 LAST CDS_LIB mstr_standard
J 0
(-6725 1325);
PAINT ORANGE (-6725 1325);
DISPLAY INVISIBLE (-6725 1325);
FORCEPROP 1 LAST BODY_TYPE PLUMBING
J 0
(-6675 1325);
DISPLAY 2.276596 (-6675 1325);
PAINT GREEN (-6675 1325);
DISPLAY INVISIBLE (-6675 1325);
FORCEPROP 1 LAST PATH I239
J 0
(-6727 1325);
DISPLAY 0.872340 (-6727 1325);
PAINT GREEN (-6727 1325);
DISPLAY INVISIBLE (-6727 1325);
FORCEPROP 1 LAST HDL_TAP TRUE
J 0
(-6405 1195);
DISPLAY 2.276596 (-6405 1195);
PAINT GREEN (-6405 1195);
DISPLAY INVISIBLE (-6405 1195);
FORCEADD CAP..1
R 2
(-6675 875);
FORCEPROP 1 LAST PART_NUMBER A36096-155
J 2
(-6725 725);
DISPLAY 0.617021 (-6725 725);
PAINT BLUE (-6725 725);
FORCEPROP 1 LAST PACK_TYPE 0402
J 2
(-6725 675);
DISPLAY 0.617021 (-6725 675);
PAINT SKYBLUE (-6725 675);
FORCEPROP 1 LAST VALUE 0.22UF
J 2
(-6725 925);
DISPLAY 0.617021 (-6725 925);
PAINT SKYBLUE (-6725 925);
FORCEPROP 1 LAST LOCATION C3P35
J 2
(-6725 975);
DISPLAY 0.617021 (-6725 975);
PAINT AQUA (-6725 975);
FORCEPROP 1 LAST MATERIAL X7R
J 2
(-6725 775);
DISPLAY 0.617021 (-6725 775);
PAINT SKYBLUE (-6725 775);
FORCEPROP 1 LAST VOLTAGE 16V
J 2
(-6725 875);
DISPLAY 0.617021 (-6725 875);
PAINT SKYBLUE (-6725 875);
FORCEPROP 1 LAST TOLERANCE 10%
J 2
(-6725 825);
DISPLAY 0.617021 (-6725 825);
PAINT SKYBLUE (-6725 825);
FORCEPROP 1 LASTPIN (-6675 775) $PN 2
J 2
(-6685 755);
DISPLAY 0.787234 (-6685 755);
PAINT ORANGE (-6685 755);
DISPLAY INVISIBLE (-6685 755);
FORCEPROP 1 LASTPIN (-6675 975) $PN 1
J 2
(-6685 955);
DISPLAY 0.787234 (-6685 955);
PAINT ORANGE (-6685 955);
DISPLAY INVISIBLE (-6685 955);
FORCEPROP 2 LAST CDS_LOCATION C3P35
J 2
(-6725 975);
DISPLAY 0.617021 (-6725 975);
PAINT AQUA (-6725 975);
DISPLAY INVISIBLE (-6725 975);
FORCEPROP 2 LAST CDS_LIB mstr_discrete
J 0
(-6675 875);
PAINT ORANGE (-6675 875);
DISPLAY INVISIBLE (-6675 875);
FORCEPROP 1 LAST PATH I240
J 2
(-6725 1025);
DISPLAY 0.978723 (-6725 1025);
PAINT WHITE (-6725 1025);
DISPLAY INVISIBLE (-6725 1025);
FORCEPROP 2 LAST $SEC 1
J 0
(-6725 1075);
DISPLAY 0.680851 (-6725 1075);
PAINT MONO (-6725 1075);
DISPLAY INVISIBLE (-6725 1075);
FORCEPROP 2 LAST CDS_SEC 1
J 0
(-6725 1075);
DISPLAY 1.021277 (-6725 1075);
PAINT ORANGE (-6725 1075);
DISPLAY INVISIBLE (-6725 1075);
FORCEADD CAP..1
R 2
(-6925 1575);
FORCEPROP 1 LAST PART_NUMBER A36096-155
J 2
(-6975 1425);
DISPLAY 0.617021 (-6975 1425);
PAINT BLUE (-6975 1425);
FORCEPROP 1 LAST PACK_TYPE 0402
J 2
(-6975 1375);
DISPLAY 0.617021 (-6975 1375);
PAINT SKYBLUE (-6975 1375);
FORCEPROP 1 LAST MATERIAL X7R
J 2
(-6975 1475);
DISPLAY 0.617021 (-6975 1475);
PAINT SKYBLUE (-6975 1475);
FORCEPROP 1 LAST TOLERANCE 10%
J 2
(-6975 1525);
DISPLAY 0.617021 (-6975 1525);
PAINT SKYBLUE (-6975 1525);
FORCEPROP 1 LAST VOLTAGE 16V
J 2
(-6975 1575);
DISPLAY 0.617021 (-6975 1575);
PAINT SKYBLUE (-6975 1575);
FORCEPROP 1 LAST VALUE 0.22UF
J 2
(-6975 1625);
DISPLAY 0.617021 (-6975 1625);
PAINT SKYBLUE (-6975 1625);
FORCEPROP 1 LAST LOCATION C3P40
J 2
(-6975 1675);
DISPLAY 0.617021 (-6975 1675);
PAINT AQUA (-6975 1675);
FORCEPROP 1 LASTPIN (-6925 1475) $PN 2
J 2
(-6935 1455);
DISPLAY 0.787234 (-6935 1455);
PAINT ORANGE (-6935 1455);
DISPLAY INVISIBLE (-6935 1455);
FORCEPROP 2 LAST CDS_LOCATION C3P40
J 2
(-6975 1675);
DISPLAY 0.617021 (-6975 1675);
PAINT AQUA (-6975 1675);
DISPLAY INVISIBLE (-6975 1675);
FORCEPROP 1 LASTPIN (-6925 1675) $PN 1
J 2
(-6935 1655);
DISPLAY 0.787234 (-6935 1655);
PAINT ORANGE (-6935 1655);
DISPLAY INVISIBLE (-6935 1655);
FORCEPROP 2 LAST $SEC 1
J 0
(-6975 1775);
DISPLAY 0.680851 (-6975 1775);
PAINT MONO (-6975 1775);
DISPLAY INVISIBLE (-6975 1775);
FORCEPROP 2 LAST CDS_LIB mstr_discrete
J 0
(-6925 1575);
PAINT ORANGE (-6925 1575);
DISPLAY INVISIBLE (-6925 1575);
FORCEPROP 2 LAST CDS_SEC 1
J 0
(-6975 1775);
DISPLAY 1.021277 (-6975 1775);
PAINT ORANGE (-6975 1775);
DISPLAY INVISIBLE (-6975 1775);
FORCEPROP 1 LAST PATH I241
J 2
(-6975 1725);
DISPLAY 0.978723 (-6975 1725);
PAINT WHITE (-6975 1725);
DISPLAY INVISIBLE (-6975 1725);
FORCEADD TAP..7
(-6925 1325);
FORCEPROP 3 LASTPIN (-6925 1375) SIG_NAME P3E_CPU0_PE1_PCH_TXN<7>
J 0
(-6915 1385);
DISPLAY 0.659574 (-6915 1385);
PAINT MONO (-6915 1385);
DISPLAY INVISIBLE (-6915 1385);
FORCEPROP 1 LASTPIN (-6925 1375) BN 7
R 1
J 0
(-6932 1323);
DISPLAY 0.617021 (-6932 1323);
PAINT GREEN (-6932 1323);
FORCEPROP 2 LAST CDS_LIB mstr_standard
J 0
(-6925 1325);
PAINT ORANGE (-6925 1325);
DISPLAY INVISIBLE (-6925 1325);
FORCEPROP 1 LAST PATH I242
J 0
(-6927 1325);
DISPLAY 0.872340 (-6927 1325);
PAINT GREEN (-6927 1325);
DISPLAY INVISIBLE (-6927 1325);
FORCEPROP 1 LAST BODY_TYPE PLUMBING
J 0
(-6875 1325);
DISPLAY 2.276596 (-6875 1325);
PAINT GREEN (-6875 1325);
DISPLAY INVISIBLE (-6875 1325);
FORCEPROP 1 LAST HDL_TAP TRUE
J 0
(-6605 1195);
DISPLAY 2.276596 (-6605 1195);
PAINT GREEN (-6605 1195);
DISPLAY INVISIBLE (-6605 1195);
FORCEADD TAP..3
(-6875 1125);
FORCEPROP 3 LASTPIN (-6875 1075) SIG_NAME P3E_CPU0_PE1_SS_TXP<7>
J 0
(-6865 1085);
DISPLAY 0.659574 (-6865 1085);
PAINT MONO (-6865 1085);
DISPLAY INVISIBLE (-6865 1085);
FORCEPROP 1 LASTPIN (-6875 1075) BN 7
R 1
J 0
(-6882 1063);
DISPLAY 0.617021 (-6882 1063);
PAINT GREEN (-6882 1063);
FORCEPROP 1 LAST HDL_TAP TRUE
J 0
(-6555 995);
DISPLAY 2.276596 (-6555 995);
PAINT GREEN (-6555 995);
DISPLAY INVISIBLE (-6555 995);
FORCEPROP 2 LAST CDS_LIB mstr_standard
J 0
(-6875 1125);
PAINT ORANGE (-6875 1125);
DISPLAY INVISIBLE (-6875 1125);
FORCEPROP 1 LAST BODY_TYPE PLUMBING
J 0
(-6825 1075);
DISPLAY 2.276596 (-6825 1075);
PAINT GREEN (-6825 1075);
DISPLAY INVISIBLE (-6825 1075);
FORCEPROP 1 LAST PATH I243
J 0
(-6877 1125);
DISPLAY 0.872340 (-6877 1125);
PAINT GREEN (-6877 1125);
DISPLAY INVISIBLE (-6877 1125);
FORCEADD OFFPAGE..1
(-7050 1175);
FORCEPROP 2 LAST $XR0 30 
J 0
(-7271 1175);
DISPLAY 0.638298 (-7271 1175);
PAINT MONO (-7271 1175);
FORCEPROP 2 LAST $XR1 107 
J 0
(-7391 1175);
DISPLAY 0.638298 (-7391 1175);
PAINT MONO (-7391 1175);
FORCEPROP 1 LAST COMMENT_BODY TRUE
J 0
(-6930 1075);
DISPLAY 2.276596 (-6930 1075);
PAINT GREEN (-6930 1075);
DISPLAY INVISIBLE (-6930 1075);
FORCEPROP 2 LAST CDS_LIB mstr_standard
J 0
(-7050 1175);
PAINT ORANGE (-7050 1175);
DISPLAY INVISIBLE (-7050 1175);
FORCEPROP 2 LAST PATH I244
J 0
(-7000 1250);
DISPLAY 1.021277 (-7000 1250);
PAINT ORANGE (-7000 1250);
DISPLAY INVISIBLE (-7000 1250);
FORCEPROP 1 LAST OFFPAGE TRUE
J 0
(-6730 1045);
PAINT GREEN (-6730 1045);
DISPLAY INVISIBLE (-6730 1045);
FORCEADD CAP..1
R 2
(-6475 575);
FORCEPROP 1 LAST LOCATION C3P30
J 2
(-6525 675);
DISPLAY 0.617021 (-6525 675);
PAINT AQUA (-6525 675);
FORCEPROP 1 LAST PART_NUMBER A36096-155
J 2
(-6525 425);
DISPLAY 0.617021 (-6525 425);
PAINT BLUE (-6525 425);
FORCEPROP 1 LAST VALUE 0.22UF
J 2
(-6525 625);
DISPLAY 0.617021 (-6525 625);
PAINT SKYBLUE (-6525 625);
FORCEPROP 1 LAST MATERIAL X7R
J 2
(-6525 475);
DISPLAY 0.617021 (-6525 475);
PAINT SKYBLUE (-6525 475);
FORCEPROP 1 LAST PACK_TYPE 0402
J 2
(-6525 375);
DISPLAY 0.617021 (-6525 375);
PAINT SKYBLUE (-6525 375);
FORCEPROP 1 LAST VOLTAGE 16V
J 2
(-6525 575);
DISPLAY 0.617021 (-6525 575);
PAINT SKYBLUE (-6525 575);
FORCEPROP 1 LAST TOLERANCE 10%
J 2
(-6525 525);
DISPLAY 0.617021 (-6525 525);
PAINT SKYBLUE (-6525 525);
FORCEPROP 1 LASTPIN (-6475 475) $PN 2
J 2
(-6485 455);
DISPLAY 0.787234 (-6485 455);
PAINT ORANGE (-6485 455);
DISPLAY INVISIBLE (-6485 455);
FORCEPROP 2 LAST CDS_LIB mstr_discrete
J 0
(-6475 575);
PAINT ORANGE (-6475 575);
DISPLAY INVISIBLE (-6475 575);
FORCEPROP 2 LAST $SEC 1
J 0
(-6525 775);
DISPLAY 0.680851 (-6525 775);
PAINT MONO (-6525 775);
DISPLAY INVISIBLE (-6525 775);
FORCEPROP 1 LASTPIN (-6475 675) $PN 1
J 2
(-6485 655);
DISPLAY 0.787234 (-6485 655);
PAINT ORANGE (-6485 655);
DISPLAY INVISIBLE (-6485 655);
FORCEPROP 2 LAST CDS_SEC 1
J 0
(-6525 775);
DISPLAY 1.021277 (-6525 775);
PAINT ORANGE (-6525 775);
DISPLAY INVISIBLE (-6525 775);
FORCEPROP 1 LAST PATH I245
J 2
(-6525 725);
DISPLAY 0.978723 (-6525 725);
PAINT WHITE (-6525 725);
DISPLAY INVISIBLE (-6525 725);
FORCEPROP 2 LAST CDS_LOCATION C3P30
J 2
(-6525 675);
DISPLAY 0.617021 (-6525 675);
PAINT AQUA (-6525 675);
DISPLAY INVISIBLE (-6525 675);
FORCEADD TAP..7
(-6475 325);
FORCEPROP 3 LASTPIN (-6475 375) SIG_NAME P3E_CPU0_PE1_PCH_TXP<5>
J 0
(-6465 385);
DISPLAY 0.659574 (-6465 385);
PAINT MONO (-6465 385);
DISPLAY INVISIBLE (-6465 385);
FORCEPROP 1 LASTPIN (-6475 375) BN 5
R 1
J 0
(-6482 323);
DISPLAY 0.617021 (-6482 323);
PAINT GREEN (-6482 323);
FORCEPROP 1 LAST PATH I246
J 0
(-6477 325);
DISPLAY 0.872340 (-6477 325);
PAINT GREEN (-6477 325);
DISPLAY INVISIBLE (-6477 325);
FORCEPROP 2 LAST CDS_LIB mstr_standard
J 0
(-6475 325);
PAINT ORANGE (-6475 325);
DISPLAY INVISIBLE (-6475 325);
FORCEPROP 1 LAST BODY_TYPE PLUMBING
J 0
(-6425 325);
DISPLAY 2.276596 (-6425 325);
PAINT GREEN (-6425 325);
DISPLAY INVISIBLE (-6425 325);
FORCEPROP 1 LAST HDL_TAP TRUE
J 0
(-6155 195);
DISPLAY 2.276596 (-6155 195);
PAINT GREEN (-6155 195);
DISPLAY INVISIBLE (-6155 195);
FORCEADD TAP..7
(-6675 325);
FORCEPROP 3 LASTPIN (-6675 375) SIG_NAME P3E_CPU0_PE1_PCH_TXP<6>
J 0
(-6665 385);
DISPLAY 0.659574 (-6665 385);
PAINT MONO (-6665 385);
DISPLAY INVISIBLE (-6665 385);
FORCEPROP 1 LASTPIN (-6675 375) BN 6
R 1
J 0
(-6682 323);
DISPLAY 0.617021 (-6682 323);
PAINT GREEN (-6682 323);
FORCEPROP 2 LAST CDS_LIB mstr_standard
J 0
(-6675 325);
PAINT ORANGE (-6675 325);
DISPLAY INVISIBLE (-6675 325);
FORCEPROP 1 LAST PATH I247
J 0
(-6677 325);
DISPLAY 0.872340 (-6677 325);
PAINT GREEN (-6677 325);
DISPLAY INVISIBLE (-6677 325);
FORCEPROP 1 LAST BODY_TYPE PLUMBING
J 0
(-6625 325);
DISPLAY 2.276596 (-6625 325);
PAINT GREEN (-6625 325);
DISPLAY INVISIBLE (-6625 325);
FORCEPROP 1 LAST HDL_TAP TRUE
J 0
(-6355 195);
DISPLAY 2.276596 (-6355 195);
PAINT GREEN (-6355 195);
DISPLAY INVISIBLE (-6355 195);
FORCEADD CAP..1
R 2
(-6875 575);
FORCEPROP 1 LAST PART_NUMBER A36096-155
J 2
(-6925 425);
DISPLAY 0.617021 (-6925 425);
PAINT BLUE (-6925 425);
FORCEPROP 1 LAST MATERIAL X7R
J 2
(-6925 475);
DISPLAY 0.617021 (-6925 475);
PAINT SKYBLUE (-6925 475);
FORCEPROP 1 LAST PACK_TYPE 0402
J 2
(-6925 375);
DISPLAY 0.617021 (-6925 375);
PAINT SKYBLUE (-6925 375);
FORCEPROP 1 LAST VOLTAGE 16V
J 2
(-6925 575);
DISPLAY 0.617021 (-6925 575);
PAINT SKYBLUE (-6925 575);
FORCEPROP 1 LAST TOLERANCE 10%
J 2
(-6925 525);
DISPLAY 0.617021 (-6925 525);
PAINT SKYBLUE (-6925 525);
FORCEPROP 1 LAST VALUE 0.22UF
J 2
(-6925 625);
DISPLAY 0.617021 (-6925 625);
PAINT SKYBLUE (-6925 625);
FORCEPROP 1 LAST LOCATION C3P39
J 2
(-6925 675);
DISPLAY 0.617021 (-6925 675);
PAINT AQUA (-6925 675);
FORCEPROP 1 LASTPIN (-6875 475) $PN 2
J 2
(-6885 455);
DISPLAY 0.787234 (-6885 455);
PAINT ORANGE (-6885 455);
DISPLAY INVISIBLE (-6885 455);
FORCEPROP 1 LAST PATH I248
J 2
(-6925 725);
DISPLAY 0.978723 (-6925 725);
PAINT WHITE (-6925 725);
DISPLAY INVISIBLE (-6925 725);
FORCEPROP 2 LAST CDS_LOCATION C3P39
J 2
(-6925 675);
DISPLAY 0.617021 (-6925 675);
PAINT AQUA (-6925 675);
DISPLAY INVISIBLE (-6925 675);
FORCEPROP 2 LAST CDS_SEC 1
J 0
(-6925 775);
DISPLAY 1.021277 (-6925 775);
PAINT ORANGE (-6925 775);
DISPLAY INVISIBLE (-6925 775);
FORCEPROP 2 LAST $SEC 1
J 0
(-6925 775);
DISPLAY 0.680851 (-6925 775);
PAINT MONO (-6925 775);
DISPLAY INVISIBLE (-6925 775);
FORCEPROP 1 LASTPIN (-6875 675) $PN 1
J 2
(-6885 655);
DISPLAY 0.787234 (-6885 655);
PAINT ORANGE (-6885 655);
DISPLAY INVISIBLE (-6885 655);
FORCEPROP 2 LAST CDS_LIB mstr_discrete
J 0
(-6875 575);
PAINT ORANGE (-6875 575);
DISPLAY INVISIBLE (-6875 575);
FORCEADD TAP..7
(-6875 325);
FORCEPROP 3 LASTPIN (-6875 375) SIG_NAME P3E_CPU0_PE1_PCH_TXP<7>
J 0
(-6865 385);
DISPLAY 0.659574 (-6865 385);
PAINT MONO (-6865 385);
DISPLAY INVISIBLE (-6865 385);
FORCEPROP 1 LASTPIN (-6875 375) BN 7
R 1
J 0
(-6882 323);
DISPLAY 0.617021 (-6882 323);
PAINT GREEN (-6882 323);
FORCEPROP 2 LAST CDS_LIB mstr_standard
J 0
(-6875 325);
PAINT ORANGE (-6875 325);
DISPLAY INVISIBLE (-6875 325);
FORCEPROP 1 LAST PATH I249
J 0
(-6877 325);
DISPLAY 0.872340 (-6877 325);
PAINT GREEN (-6877 325);
DISPLAY INVISIBLE (-6877 325);
FORCEPROP 1 LAST BODY_TYPE PLUMBING
J 0
(-6825 325);
DISPLAY 2.276596 (-6825 325);
PAINT GREEN (-6825 325);
DISPLAY INVISIBLE (-6825 325);
FORCEPROP 1 LAST HDL_TAP TRUE
J 0
(-6555 195);
DISPLAY 2.276596 (-6555 195);
PAINT GREEN (-6555 195);
DISPLAY INVISIBLE (-6555 195);
FORCEADD TAP..3
(-1950 2075);
FORCEPROP 3 LASTPIN (-1950 2025) SIG_NAME P3E_CPU0_PE1_PCH_RXN<0>
J 0
(-1940 2035);
DISPLAY 0.659574 (-1940 2035);
PAINT MONO (-1940 2035);
DISPLAY INVISIBLE (-1940 2035);
FORCEPROP 1 LASTPIN (-1950 2025) BN 0
R 1
J 0
(-1957 2013);
DISPLAY 0.617021 (-1957 2013);
PAINT GREEN (-1957 2013);
FORCEPROP 1 LAST HDL_TAP TRUE
J 0
(-1630 1945);
DISPLAY 2.276596 (-1630 1945);
PAINT GREEN (-1630 1945);
DISPLAY INVISIBLE (-1630 1945);
FORCEPROP 1 LAST BODY_TYPE PLUMBING
J 0
(-1900 2025);
DISPLAY 2.276596 (-1900 2025);
PAINT GREEN (-1900 2025);
DISPLAY INVISIBLE (-1900 2025);
FORCEPROP 2 LAST CDS_LIB mstr_standard
J 0
(-1950 2075);
PAINT ORANGE (-1950 2075);
DISPLAY INVISIBLE (-1950 2075);
FORCEPROP 1 LAST PATH I250
J 0
(-1952 2075);
DISPLAY 0.872340 (-1952 2075);
PAINT GREEN (-1952 2075);
DISPLAY INVISIBLE (-1952 2075);
FORCEADD TAP..3
(-2150 2075);
FORCEPROP 3 LASTPIN (-2150 2025) SIG_NAME P3E_CPU0_PE1_PCH_RXN<1>
J 0
(-2140 2035);
DISPLAY 0.659574 (-2140 2035);
PAINT MONO (-2140 2035);
DISPLAY INVISIBLE (-2140 2035);
FORCEPROP 1 LASTPIN (-2150 2025) BN 1
R 1
J 0
(-2157 2013);
DISPLAY 0.617021 (-2157 2013);
PAINT GREEN (-2157 2013);
FORCEPROP 1 LAST BODY_TYPE PLUMBING
J 0
(-2100 2025);
DISPLAY 2.276596 (-2100 2025);
PAINT GREEN (-2100 2025);
DISPLAY INVISIBLE (-2100 2025);
FORCEPROP 2 LAST CDS_LIB mstr_standard
J 0
(-2150 2075);
PAINT ORANGE (-2150 2075);
DISPLAY INVISIBLE (-2150 2075);
FORCEPROP 1 LAST PATH I251
J 0
(-2152 2075);
DISPLAY 0.872340 (-2152 2075);
PAINT GREEN (-2152 2075);
DISPLAY INVISIBLE (-2152 2075);
FORCEPROP 1 LAST HDL_TAP TRUE
J 0
(-1830 1945);
DISPLAY 2.276596 (-1830 1945);
PAINT GREEN (-1830 1945);
DISPLAY INVISIBLE (-1830 1945);
FORCEADD TAP..3
(-2350 2075);
FORCEPROP 3 LASTPIN (-2350 2025) SIG_NAME P3E_CPU0_PE1_PCH_RXN<2>
J 0
(-2340 2035);
DISPLAY 0.659574 (-2340 2035);
PAINT MONO (-2340 2035);
DISPLAY INVISIBLE (-2340 2035);
FORCEPROP 1 LASTPIN (-2350 2025) BN 2
R 1
J 0
(-2357 2013);
DISPLAY 0.617021 (-2357 2013);
PAINT GREEN (-2357 2013);
FORCEPROP 1 LAST BODY_TYPE PLUMBING
J 0
(-2300 2025);
DISPLAY 2.276596 (-2300 2025);
PAINT GREEN (-2300 2025);
DISPLAY INVISIBLE (-2300 2025);
FORCEPROP 1 LAST PATH I252
J 0
(-2352 2075);
DISPLAY 0.872340 (-2352 2075);
PAINT GREEN (-2352 2075);
DISPLAY INVISIBLE (-2352 2075);
FORCEPROP 2 LAST CDS_LIB mstr_standard
J 0
(-2350 2075);
PAINT ORANGE (-2350 2075);
DISPLAY INVISIBLE (-2350 2075);
FORCEPROP 1 LAST HDL_TAP TRUE
J 0
(-2030 1945);
DISPLAY 2.276596 (-2030 1945);
PAINT GREEN (-2030 1945);
DISPLAY INVISIBLE (-2030 1945);
FORCEADD TAP..3
(-2550 2075);
FORCEPROP 3 LASTPIN (-2550 2025) SIG_NAME P3E_CPU0_PE1_PCH_RXN<3>
J 0
(-2540 2035);
DISPLAY 0.659574 (-2540 2035);
PAINT MONO (-2540 2035);
DISPLAY INVISIBLE (-2540 2035);
FORCEPROP 1 LASTPIN (-2550 2025) BN 3
R 1
J 0
(-2557 2013);
DISPLAY 0.617021 (-2557 2013);
PAINT GREEN (-2557 2013);
FORCEPROP 1 LAST HDL_TAP TRUE
J 0
(-2230 1945);
DISPLAY 2.276596 (-2230 1945);
PAINT GREEN (-2230 1945);
DISPLAY INVISIBLE (-2230 1945);
FORCEPROP 1 LAST BODY_TYPE PLUMBING
J 0
(-2500 2025);
DISPLAY 2.276596 (-2500 2025);
PAINT GREEN (-2500 2025);
DISPLAY INVISIBLE (-2500 2025);
FORCEPROP 1 LAST PATH I253
J 0
(-2552 2075);
DISPLAY 0.872340 (-2552 2075);
PAINT GREEN (-2552 2075);
DISPLAY INVISIBLE (-2552 2075);
FORCEPROP 2 LAST CDS_LIB mstr_standard
J 0
(-2550 2075);
PAINT ORANGE (-2550 2075);
DISPLAY INVISIBLE (-2550 2075);
FORCEADD TAP..3
(-2750 2075);
FORCEPROP 3 LASTPIN (-2750 2025) SIG_NAME P3E_CPU0_PE1_PCH_RXN<4>
J 0
(-2740 2035);
DISPLAY 0.659574 (-2740 2035);
PAINT MONO (-2740 2035);
DISPLAY INVISIBLE (-2740 2035);
FORCEPROP 1 LASTPIN (-2750 2025) BN 4
R 1
J 0
(-2757 2013);
DISPLAY 0.617021 (-2757 2013);
PAINT GREEN (-2757 2013);
FORCEPROP 1 LAST HDL_TAP TRUE
J 0
(-2430 1945);
DISPLAY 2.276596 (-2430 1945);
PAINT GREEN (-2430 1945);
DISPLAY INVISIBLE (-2430 1945);
FORCEPROP 1 LAST BODY_TYPE PLUMBING
J 0
(-2700 2025);
DISPLAY 2.276596 (-2700 2025);
PAINT GREEN (-2700 2025);
DISPLAY INVISIBLE (-2700 2025);
FORCEPROP 2 LAST CDS_LIB mstr_standard
J 0
(-2750 2075);
PAINT ORANGE (-2750 2075);
DISPLAY INVISIBLE (-2750 2075);
FORCEPROP 1 LAST PATH I254
J 0
(-2752 2075);
DISPLAY 0.872340 (-2752 2075);
PAINT GREEN (-2752 2075);
DISPLAY INVISIBLE (-2752 2075);
FORCEADD OFFPAGE..2
(-1700 1225);
FORCEPROP 2 LAST $XR0 107 
J 0
(-1511 1225);
DISPLAY 0.638298 (-1511 1225);
PAINT MONO (-1511 1225);
FORCEPROP 2 LAST $XR1 30 
J 0
(-1391 1225);
DISPLAY 0.638298 (-1391 1225);
PAINT MONO (-1391 1225);
FORCEPROP 1 LAST COMMENT_BODY TRUE
J 0
(-1745 1130);
DISPLAY 0.872340 (-1745 1130);
PAINT GREEN (-1745 1130);
DISPLAY INVISIBLE (-1745 1130);
FORCEPROP 2 LAST CDS_LIB mstr_standard
J 0
(-1700 1225);
PAINT ORANGE (-1700 1225);
DISPLAY INVISIBLE (-1700 1225);
FORCEPROP 2 LAST PATH I255
J 0
(-1525 1300);
DISPLAY 1.021277 (-1525 1300);
PAINT ORANGE (-1525 1300);
DISPLAY INVISIBLE (-1525 1300);
FORCEPROP 1 LAST OFFPAGE TRUE
J 0
(-1375 1100);
DISPLAY 0.872340 (-1375 1100);
PAINT GREEN (-1375 1100);
DISPLAY INVISIBLE (-1375 1100);
FORCEADD OFFPAGE..2
(-1675 225);
FORCEPROP 2 LAST $XR0 107 
J 0
(-1486 225);
DISPLAY 0.638298 (-1486 225);
PAINT MONO (-1486 225);
FORCEPROP 2 LAST $XR1 30 
J 0
(-1366 225);
DISPLAY 0.638298 (-1366 225);
PAINT MONO (-1366 225);
FORCEPROP 1 LAST COMMENT_BODY TRUE
J 0
(-1720 130);
DISPLAY 0.872340 (-1720 130);
PAINT GREEN (-1720 130);
DISPLAY INVISIBLE (-1720 130);
FORCEPROP 2 LAST CDS_LIB mstr_standard
J 0
(-1675 225);
PAINT ORANGE (-1675 225);
DISPLAY INVISIBLE (-1675 225);
FORCEPROP 2 LAST PATH I256
J 0
(-1500 300);
DISPLAY 1.021277 (-1500 300);
PAINT ORANGE (-1500 300);
DISPLAY INVISIBLE (-1500 300);
FORCEPROP 1 LAST OFFPAGE TRUE
J 0
(-1350 100);
DISPLAY 0.872340 (-1350 100);
PAINT GREEN (-1350 100);
DISPLAY INVISIBLE (-1350 100);
FORCEADD CAP..1
R 2
(-1950 1825);
FORCEPROP 1 LAST PACK_TYPE 0402
J 2
(-2000 1675);
DISPLAY 0.617021 (-2000 1675);
PAINT SKYBLUE (-2000 1675);
FORCEPROP 1 LAST LOCATION C2U4
J 2
(-2000 1925);
DISPLAY 0.617021 (-2000 1925);
PAINT AQUA (-2000 1925);
FORCEPROP 1 LAST VALUE 0.22UF
J 2
(-2000 1875);
DISPLAY 0.617021 (-2000 1875);
PAINT SKYBLUE (-2000 1875);
FORCEPROP 1 LAST TOLERANCE 10%
J 2
(-2000 1775);
DISPLAY 0.617021 (-2000 1775);
PAINT SKYBLUE (-2000 1775);
FORCEPROP 1 LAST MATERIAL X7R
J 2
(-2000 1725);
DISPLAY 0.617021 (-2000 1725);
PAINT SKYBLUE (-2000 1725);
FORCEPROP 1 LAST VOLTAGE 16V
J 2
(-2000 1825);
DISPLAY 0.617021 (-2000 1825);
PAINT SKYBLUE (-2000 1825);
FORCEPROP 1 LAST PART_NUMBER A36096-155
R 1
J 2
(-1900 1625);
DISPLAY 0.617021 (-1900 1625);
PAINT BLUE (-1900 1625);
FORCEPROP 1 LASTPIN (-1950 1725) $PN 2
J 2
(-1955 1735);
DISPLAY 0.617021 (-1955 1735);
PAINT ORANGE (-1955 1735);
FORCEPROP 1 LASTPIN (-1950 1925) $PN 1
J 2
(-1955 1887);
DISPLAY 0.617021 (-1955 1887);
PAINT ORANGE (-1955 1887);
FORCEPROP 1 LAST PATH I257
J 2
(-2000 1975);
DISPLAY 0.978723 (-2000 1975);
PAINT WHITE (-2000 1975);
DISPLAY INVISIBLE (-2000 1975);
FORCEPROP 2 LAST CDS_LOCATION C2U4
J 0
(-2000 1975);
DISPLAY 0.617021 (-2000 1975);
PAINT AQUA (-2000 1975);
DISPLAY INVISIBLE (-2000 1975);
FORCEPROP 2 LAST CDS_LIB mstr_discrete
J 0
(-1950 1825);
PAINT MONO (-1950 1825);
DISPLAY INVISIBLE (-1950 1825);
FORCEPROP 2 LAST SEC_TYPE 0402
J 0
(-2000 2025);
DISPLAY 1.021277 (-2000 2025);
PAINT ORANGE (-2000 2025);
DISPLAY INVISIBLE (-2000 2025);
FORCEPROP 2 LAST SEC 1
J 0
(-2000 2050);
DISPLAY 0.680851 (-2000 2050);
PAINT MONO (-2000 2050);
DISPLAY INVISIBLE (-2000 2050);
FORCEADD TAP..3
(-1900 1075);
FORCEPROP 3 LASTPIN (-1900 1025) SIG_NAME P3E_CPU0_PE1_PCH_RXP<0>
J 0
(-1890 1035);
DISPLAY 0.659574 (-1890 1035);
PAINT MONO (-1890 1035);
DISPLAY INVISIBLE (-1890 1035);
FORCEPROP 1 LASTPIN (-1900 1025) BN 0
R 1
J 0
(-1907 1013);
DISPLAY 0.617021 (-1907 1013);
PAINT GREEN (-1907 1013);
FORCEPROP 1 LAST HDL_TAP TRUE
J 0
(-1580 945);
DISPLAY 2.276596 (-1580 945);
PAINT GREEN (-1580 945);
DISPLAY INVISIBLE (-1580 945);
FORCEPROP 1 LAST PATH I258
J 0
(-1902 1075);
DISPLAY 0.872340 (-1902 1075);
PAINT GREEN (-1902 1075);
DISPLAY INVISIBLE (-1902 1075);
FORCEPROP 1 LAST BODY_TYPE PLUMBING
J 0
(-1850 1025);
DISPLAY 2.276596 (-1850 1025);
PAINT GREEN (-1850 1025);
DISPLAY INVISIBLE (-1850 1025);
FORCEPROP 2 LAST CDS_LIB mstr_standard
J 0
(-1900 1075);
PAINT ORANGE (-1900 1075);
DISPLAY INVISIBLE (-1900 1075);
FORCEADD TAP..7
(-1950 1275);
FORCEPROP 3 LASTPIN (-1950 1325) SIG_NAME P3E_CPU0_PE1_SS_RXN<0>
J 0
(-1940 1335);
DISPLAY 0.659574 (-1940 1335);
PAINT MONO (-1940 1335);
DISPLAY INVISIBLE (-1940 1335);
FORCEPROP 1 LASTPIN (-1950 1325) BN 0
R 1
J 0
(-1957 1273);
DISPLAY 0.617021 (-1957 1273);
PAINT GREEN (-1957 1273);
FORCEPROP 1 LAST BODY_TYPE PLUMBING
J 0
(-1900 1275);
DISPLAY 2.276596 (-1900 1275);
PAINT GREEN (-1900 1275);
DISPLAY INVISIBLE (-1900 1275);
FORCEPROP 2 LAST CDS_LIB mstr_standard
J 0
(-1950 1275);
PAINT ORANGE (-1950 1275);
DISPLAY INVISIBLE (-1950 1275);
FORCEPROP 1 LAST PATH I259
J 0
(-1952 1275);
DISPLAY 0.872340 (-1952 1275);
PAINT GREEN (-1952 1275);
DISPLAY INVISIBLE (-1952 1275);
FORCEPROP 1 LAST HDL_TAP TRUE
J 0
(-1630 1145);
DISPLAY 2.276596 (-1630 1145);
PAINT GREEN (-1630 1145);
DISPLAY INVISIBLE (-1630 1145);
FORCEADD CAP..1
R 2
(-2150 1525);
FORCEPROP 1 LAST PACK_TYPE 0402
J 2
(-2200 1375);
DISPLAY 0.617021 (-2200 1375);
PAINT SKYBLUE (-2200 1375);
FORCEPROP 1 LAST TOLERANCE 10%
J 2
(-2200 1475);
DISPLAY 0.617021 (-2200 1475);
PAINT SKYBLUE (-2200 1475);
FORCEPROP 1 LASTPIN (-2150 1425) $PN 2
J 2
(-2155 1435);
DISPLAY 0.617021 (-2155 1435);
PAINT ORANGE (-2155 1435);
FORCEPROP 1 LAST MATERIAL X7R
J 2
(-2200 1425);
DISPLAY 0.617021 (-2200 1425);
PAINT SKYBLUE (-2200 1425);
FORCEPROP 1 LAST VOLTAGE 16V
J 2
(-2200 1525);
DISPLAY 0.617021 (-2200 1525);
PAINT SKYBLUE (-2200 1525);
FORCEPROP 1 LAST LOCATION C2U6
J 2
(-2200 1625);
DISPLAY 0.617021 (-2200 1625);
PAINT AQUA (-2200 1625);
FORCEPROP 1 LAST VALUE 0.22UF
J 2
(-2200 1575);
DISPLAY 0.617021 (-2200 1575);
PAINT SKYBLUE (-2200 1575);
FORCEPROP 1 LAST PART_NUMBER A36096-155
R 1
J 2
(-2175 1925);
DISPLAY 0.617021 (-2175 1925);
PAINT BLUE (-2175 1925);
FORCEPROP 1 LASTPIN (-2150 1625) $PN 1
J 2
(-2155 1587);
DISPLAY 0.617021 (-2155 1587);
PAINT ORANGE (-2155 1587);
FORCEPROP 2 LAST CDS_LIB mstr_discrete
J 0
(-2150 1525);
PAINT MONO (-2150 1525);
DISPLAY INVISIBLE (-2150 1525);
FORCEPROP 2 LAST SEC_TYPE 0402
J 0
(-2200 1725);
DISPLAY 1.021277 (-2200 1725);
PAINT ORANGE (-2200 1725);
DISPLAY INVISIBLE (-2200 1725);
FORCEPROP 2 LAST SEC 1
J 0
(-2200 1750);
DISPLAY 0.680851 (-2200 1750);
PAINT MONO (-2200 1750);
DISPLAY INVISIBLE (-2200 1750);
FORCEPROP 2 LAST CDS_LOCATION C2U6
J 0
(-2200 1675);
DISPLAY 0.617021 (-2200 1675);
PAINT AQUA (-2200 1675);
DISPLAY INVISIBLE (-2200 1675);
FORCEPROP 1 LAST PATH I260
J 2
(-2200 1675);
DISPLAY 0.978723 (-2200 1675);
PAINT WHITE (-2200 1675);
DISPLAY INVISIBLE (-2200 1675);
FORCEADD TAP..3
(-2100 1075);
FORCEPROP 3 LASTPIN (-2100 1025) SIG_NAME P3E_CPU0_PE1_PCH_RXP<1>
J 0
(-2090 1035);
DISPLAY 0.659574 (-2090 1035);
PAINT MONO (-2090 1035);
DISPLAY INVISIBLE (-2090 1035);
FORCEPROP 1 LASTPIN (-2100 1025) BN 1
R 1
J 0
(-2107 1013);
DISPLAY 0.617021 (-2107 1013);
PAINT GREEN (-2107 1013);
FORCEPROP 1 LAST PATH I261
J 0
(-2102 1075);
DISPLAY 0.872340 (-2102 1075);
PAINT GREEN (-2102 1075);
DISPLAY INVISIBLE (-2102 1075);
FORCEPROP 1 LAST BODY_TYPE PLUMBING
J 0
(-2050 1025);
DISPLAY 2.276596 (-2050 1025);
PAINT GREEN (-2050 1025);
DISPLAY INVISIBLE (-2050 1025);
FORCEPROP 2 LAST CDS_LIB mstr_standard
J 0
(-2100 1075);
PAINT ORANGE (-2100 1075);
DISPLAY INVISIBLE (-2100 1075);
FORCEPROP 1 LAST HDL_TAP TRUE
J 0
(-1780 945);
DISPLAY 2.276596 (-1780 945);
PAINT GREEN (-1780 945);
DISPLAY INVISIBLE (-1780 945);
FORCEADD TAP..7
(-2150 1275);
FORCEPROP 3 LASTPIN (-2150 1325) SIG_NAME P3E_CPU0_PE1_SS_RXN<1>
J 0
(-2140 1335);
DISPLAY 0.659574 (-2140 1335);
PAINT MONO (-2140 1335);
DISPLAY INVISIBLE (-2140 1335);
FORCEPROP 1 LASTPIN (-2150 1325) BN 1
R 1
J 0
(-2157 1273);
DISPLAY 0.617021 (-2157 1273);
PAINT GREEN (-2157 1273);
FORCEPROP 2 LAST CDS_LIB mstr_standard
J 0
(-2150 1275);
PAINT ORANGE (-2150 1275);
DISPLAY INVISIBLE (-2150 1275);
FORCEPROP 1 LAST BODY_TYPE PLUMBING
J 0
(-2100 1275);
DISPLAY 2.276596 (-2100 1275);
PAINT GREEN (-2100 1275);
DISPLAY INVISIBLE (-2100 1275);
FORCEPROP 1 LAST PATH I262
J 0
(-2152 1275);
DISPLAY 0.872340 (-2152 1275);
PAINT GREEN (-2152 1275);
DISPLAY INVISIBLE (-2152 1275);
FORCEPROP 1 LAST HDL_TAP TRUE
J 0
(-1830 1145);
DISPLAY 2.276596 (-1830 1145);
PAINT GREEN (-1830 1145);
DISPLAY INVISIBLE (-1830 1145);
FORCEADD TAP..3
(-2300 1075);
FORCEPROP 3 LASTPIN (-2300 1025) SIG_NAME P3E_CPU0_PE1_PCH_RXP<2>
J 0
(-2290 1035);
DISPLAY 0.659574 (-2290 1035);
PAINT MONO (-2290 1035);
DISPLAY INVISIBLE (-2290 1035);
FORCEPROP 1 LASTPIN (-2300 1025) BN 2
R 1
J 0
(-2307 1013);
DISPLAY 0.617021 (-2307 1013);
PAINT GREEN (-2307 1013);
FORCEPROP 1 LAST PATH I263
J 0
(-2302 1075);
DISPLAY 0.872340 (-2302 1075);
PAINT GREEN (-2302 1075);
DISPLAY INVISIBLE (-2302 1075);
FORCEPROP 1 LAST BODY_TYPE PLUMBING
J 0
(-2250 1025);
DISPLAY 2.276596 (-2250 1025);
PAINT GREEN (-2250 1025);
DISPLAY INVISIBLE (-2250 1025);
FORCEPROP 2 LAST CDS_LIB mstr_standard
J 0
(-2300 1075);
PAINT ORANGE (-2300 1075);
DISPLAY INVISIBLE (-2300 1075);
FORCEPROP 1 LAST HDL_TAP TRUE
J 0
(-1980 945);
DISPLAY 2.276596 (-1980 945);
PAINT GREEN (-1980 945);
DISPLAY INVISIBLE (-1980 945);
FORCEADD CAP..1
R 2
(-2350 1825);
FORCEPROP 1 LAST VALUE 0.22UF
J 2
(-2400 1875);
DISPLAY 0.617021 (-2400 1875);
PAINT SKYBLUE (-2400 1875);
FORCEPROP 1 LAST PART_NUMBER A36096-155
R 1
J 2
(-2375 1625);
DISPLAY 0.617021 (-2375 1625);
PAINT BLUE (-2375 1625);
FORCEPROP 1 LAST MATERIAL X7R
J 2
(-2400 1725);
DISPLAY 0.617021 (-2400 1725);
PAINT SKYBLUE (-2400 1725);
FORCEPROP 1 LASTPIN (-2350 1725) $PN 2
J 2
(-2355 1735);
DISPLAY 0.617021 (-2355 1735);
PAINT ORANGE (-2355 1735);
FORCEPROP 1 LAST PACK_TYPE 0402
J 2
(-2400 1675);
DISPLAY 0.617021 (-2400 1675);
PAINT SKYBLUE (-2400 1675);
FORCEPROP 1 LAST TOLERANCE 10%
J 2
(-2400 1775);
DISPLAY 0.617021 (-2400 1775);
PAINT SKYBLUE (-2400 1775);
FORCEPROP 1 LAST VOLTAGE 16V
J 2
(-2400 1825);
DISPLAY 0.617021 (-2400 1825);
PAINT SKYBLUE (-2400 1825);
FORCEPROP 1 LAST LOCATION C2U8
J 2
(-2400 1925);
DISPLAY 0.617021 (-2400 1925);
PAINT AQUA (-2400 1925);
FORCEPROP 1 LASTPIN (-2350 1925) $PN 1
J 2
(-2355 1887);
DISPLAY 0.617021 (-2355 1887);
PAINT ORANGE (-2355 1887);
FORCEPROP 2 LAST CDS_LIB mstr_discrete
J 0
(-2350 1825);
PAINT MONO (-2350 1825);
DISPLAY INVISIBLE (-2350 1825);
FORCEPROP 2 LAST CDS_LOCATION C2U8
J 0
(-2400 1975);
DISPLAY 0.617021 (-2400 1975);
PAINT AQUA (-2400 1975);
DISPLAY INVISIBLE (-2400 1975);
FORCEPROP 1 LAST PATH I264
J 2
(-2400 1975);
DISPLAY 0.978723 (-2400 1975);
PAINT WHITE (-2400 1975);
DISPLAY INVISIBLE (-2400 1975);
FORCEPROP 2 LAST SEC_TYPE 0402
J 0
(-2400 2025);
DISPLAY 1.021277 (-2400 2025);
PAINT ORANGE (-2400 2025);
DISPLAY INVISIBLE (-2400 2025);
FORCEPROP 2 LAST SEC 1
J 0
(-2400 2050);
DISPLAY 0.680851 (-2400 2050);
PAINT MONO (-2400 2050);
DISPLAY INVISIBLE (-2400 2050);
FORCEADD CAP..1
R 2
(-2750 1825);
FORCEPROP 1 LAST PART_NUMBER A36096-155
R 1
J 2
(-2775 1650);
DISPLAY 0.617021 (-2775 1650);
PAINT BLUE (-2775 1650);
FORCEPROP 1 LAST PACK_TYPE 0402
J 2
(-2800 1675);
DISPLAY 0.617021 (-2800 1675);
PAINT SKYBLUE (-2800 1675);
FORCEPROP 1 LAST LOCATION C2U12
J 2
(-2800 1925);
DISPLAY 0.617021 (-2800 1925);
PAINT AQUA (-2800 1925);
FORCEPROP 1 LAST TOLERANCE 10%
J 2
(-2800 1775);
DISPLAY 0.617021 (-2800 1775);
PAINT SKYBLUE (-2800 1775);
FORCEPROP 1 LAST MATERIAL X7R
J 2
(-2800 1725);
DISPLAY 0.617021 (-2800 1725);
PAINT SKYBLUE (-2800 1725);
FORCEPROP 1 LAST VOLTAGE 16V
J 2
(-2800 1825);
DISPLAY 0.617021 (-2800 1825);
PAINT SKYBLUE (-2800 1825);
FORCEPROP 1 LAST VALUE 0.22UF
J 2
(-2800 1875);
DISPLAY 0.617021 (-2800 1875);
PAINT SKYBLUE (-2800 1875);
FORCEPROP 1 LASTPIN (-2750 1725) $PN 2
J 2
(-2755 1735);
DISPLAY 0.617021 (-2755 1735);
PAINT ORANGE (-2755 1735);
FORCEPROP 1 LASTPIN (-2750 1925) $PN 1
J 2
(-2755 1887);
DISPLAY 0.617021 (-2755 1887);
PAINT ORANGE (-2755 1887);
FORCEPROP 2 LAST CDS_LOCATION C2U12
J 0
(-2800 1975);
DISPLAY 0.617021 (-2800 1975);
PAINT AQUA (-2800 1975);
DISPLAY INVISIBLE (-2800 1975);
FORCEPROP 1 LAST PATH I265
J 2
(-2800 1975);
DISPLAY 0.978723 (-2800 1975);
PAINT WHITE (-2800 1975);
DISPLAY INVISIBLE (-2800 1975);
FORCEPROP 2 LAST CDS_LIB mstr_discrete
J 0
(-2750 1825);
PAINT MONO (-2750 1825);
DISPLAY INVISIBLE (-2750 1825);
FORCEPROP 2 LAST SEC_TYPE 0402
J 0
(-2800 2025);
DISPLAY 1.021277 (-2800 2025);
PAINT ORANGE (-2800 2025);
DISPLAY INVISIBLE (-2800 2025);
FORCEPROP 2 LAST SEC 1
J 0
(-2800 2050);
DISPLAY 0.680851 (-2800 2050);
PAINT MONO (-2800 2050);
DISPLAY INVISIBLE (-2800 2050);
FORCEADD TAP..7
(-2350 1275);
FORCEPROP 3 LASTPIN (-2350 1325) SIG_NAME P3E_CPU0_PE1_SS_RXN<2>
J 0
(-2340 1335);
DISPLAY 0.659574 (-2340 1335);
PAINT MONO (-2340 1335);
DISPLAY INVISIBLE (-2340 1335);
FORCEPROP 1 LASTPIN (-2350 1325) BN 2
R 1
J 0
(-2357 1273);
DISPLAY 0.617021 (-2357 1273);
PAINT GREEN (-2357 1273);
FORCEPROP 2 LAST CDS_LIB mstr_standard
J 0
(-2350 1275);
PAINT ORANGE (-2350 1275);
DISPLAY INVISIBLE (-2350 1275);
FORCEPROP 1 LAST PATH I266
J 0
(-2352 1275);
DISPLAY 0.872340 (-2352 1275);
PAINT GREEN (-2352 1275);
DISPLAY INVISIBLE (-2352 1275);
FORCEPROP 1 LAST BODY_TYPE PLUMBING
J 0
(-2300 1275);
DISPLAY 2.276596 (-2300 1275);
PAINT GREEN (-2300 1275);
DISPLAY INVISIBLE (-2300 1275);
FORCEPROP 1 LAST HDL_TAP TRUE
J 0
(-2030 1145);
DISPLAY 2.276596 (-2030 1145);
PAINT GREEN (-2030 1145);
DISPLAY INVISIBLE (-2030 1145);
FORCEADD CAP..1
R 2
(-2550 1525);
FORCEPROP 1 LAST PACK_TYPE 0402
J 2
(-2600 1375);
DISPLAY 0.617021 (-2600 1375);
PAINT SKYBLUE (-2600 1375);
FORCEPROP 1 LAST MATERIAL X7R
J 2
(-2600 1425);
DISPLAY 0.617021 (-2600 1425);
PAINT SKYBLUE (-2600 1425);
FORCEPROP 1 LAST TOLERANCE 10%
J 2
(-2600 1475);
DISPLAY 0.617021 (-2600 1475);
PAINT SKYBLUE (-2600 1475);
FORCEPROP 1 LAST VOLTAGE 16V
J 2
(-2600 1525);
DISPLAY 0.617021 (-2600 1525);
PAINT SKYBLUE (-2600 1525);
FORCEPROP 1 LAST LOCATION C2U10
J 2
(-2600 1625);
DISPLAY 0.617021 (-2600 1625);
PAINT AQUA (-2600 1625);
FORCEPROP 1 LAST VALUE 0.22UF
J 2
(-2600 1575);
DISPLAY 0.617021 (-2600 1575);
PAINT SKYBLUE (-2600 1575);
FORCEPROP 1 LAST PART_NUMBER A36096-155
R 1
J 2
(-2575 1900);
DISPLAY 0.617021 (-2575 1900);
PAINT BLUE (-2575 1900);
FORCEPROP 1 LASTPIN (-2550 1425) $PN 2
J 2
(-2555 1435);
DISPLAY 0.617021 (-2555 1435);
PAINT ORANGE (-2555 1435);
FORCEPROP 1 LASTPIN (-2550 1625) $PN 1
J 2
(-2555 1587);
DISPLAY 0.617021 (-2555 1587);
PAINT ORANGE (-2555 1587);
FORCEPROP 1 LAST PATH I267
J 2
(-2600 1675);
DISPLAY 0.978723 (-2600 1675);
PAINT WHITE (-2600 1675);
DISPLAY INVISIBLE (-2600 1675);
FORCEPROP 2 LAST CDS_LOCATION C2U10
J 0
(-2600 1675);
DISPLAY 0.617021 (-2600 1675);
PAINT AQUA (-2600 1675);
DISPLAY INVISIBLE (-2600 1675);
FORCEPROP 2 LAST SEC 1
J 0
(-2600 1750);
DISPLAY 0.680851 (-2600 1750);
PAINT MONO (-2600 1750);
DISPLAY INVISIBLE (-2600 1750);
FORCEPROP 2 LAST SEC_TYPE 0402
J 0
(-2600 1725);
DISPLAY 1.021277 (-2600 1725);
PAINT ORANGE (-2600 1725);
DISPLAY INVISIBLE (-2600 1725);
FORCEPROP 2 LAST CDS_LIB mstr_discrete
J 0
(-2550 1525);
PAINT MONO (-2550 1525);
DISPLAY INVISIBLE (-2550 1525);
FORCEADD TAP..7
(-2550 1275);
FORCEPROP 3 LASTPIN (-2550 1325) SIG_NAME P3E_CPU0_PE1_SS_RXN<3>
J 0
(-2540 1335);
DISPLAY 0.659574 (-2540 1335);
PAINT MONO (-2540 1335);
DISPLAY INVISIBLE (-2540 1335);
FORCEPROP 1 LASTPIN (-2550 1325) BN 3
R 1
J 0
(-2557 1273);
DISPLAY 0.617021 (-2557 1273);
PAINT GREEN (-2557 1273);
FORCEPROP 2 LAST CDS_LIB mstr_standard
J 0
(-2550 1275);
PAINT ORANGE (-2550 1275);
DISPLAY INVISIBLE (-2550 1275);
FORCEPROP 1 LAST BODY_TYPE PLUMBING
J 0
(-2500 1275);
DISPLAY 2.276596 (-2500 1275);
PAINT GREEN (-2500 1275);
DISPLAY INVISIBLE (-2500 1275);
FORCEPROP 1 LAST PATH I268
J 0
(-2552 1275);
DISPLAY 0.872340 (-2552 1275);
PAINT GREEN (-2552 1275);
DISPLAY INVISIBLE (-2552 1275);
FORCEPROP 1 LAST HDL_TAP TRUE
J 0
(-2230 1145);
DISPLAY 2.276596 (-2230 1145);
PAINT GREEN (-2230 1145);
DISPLAY INVISIBLE (-2230 1145);
FORCEADD TAP..3
(-2500 1075);
FORCEPROP 3 LASTPIN (-2500 1025) SIG_NAME P3E_CPU0_PE1_PCH_RXP<3>
J 0
(-2490 1035);
DISPLAY 0.659574 (-2490 1035);
PAINT MONO (-2490 1035);
DISPLAY INVISIBLE (-2490 1035);
FORCEPROP 1 LASTPIN (-2500 1025) BN 3
R 1
J 0
(-2507 1013);
DISPLAY 0.617021 (-2507 1013);
PAINT GREEN (-2507 1013);
FORCEPROP 1 LAST HDL_TAP TRUE
J 0
(-2180 945);
DISPLAY 2.276596 (-2180 945);
PAINT GREEN (-2180 945);
DISPLAY INVISIBLE (-2180 945);
FORCEPROP 1 LAST PATH I269
J 0
(-2502 1075);
DISPLAY 0.872340 (-2502 1075);
PAINT GREEN (-2502 1075);
DISPLAY INVISIBLE (-2502 1075);
FORCEPROP 1 LAST BODY_TYPE PLUMBING
J 0
(-2450 1025);
DISPLAY 2.276596 (-2450 1025);
PAINT GREEN (-2450 1025);
DISPLAY INVISIBLE (-2450 1025);
FORCEPROP 2 LAST CDS_LIB mstr_standard
J 0
(-2500 1075);
PAINT ORANGE (-2500 1075);
DISPLAY INVISIBLE (-2500 1075);
FORCEADD TAP..3
(-2700 1075);
FORCEPROP 3 LASTPIN (-2700 1025) SIG_NAME P3E_CPU0_PE1_PCH_RXP<4>
J 0
(-2690 1035);
DISPLAY 0.659574 (-2690 1035);
PAINT MONO (-2690 1035);
DISPLAY INVISIBLE (-2690 1035);
FORCEPROP 1 LASTPIN (-2700 1025) BN 4
R 1
J 0
(-2707 1013);
DISPLAY 0.617021 (-2707 1013);
PAINT GREEN (-2707 1013);
FORCEPROP 1 LAST HDL_TAP TRUE
J 0
(-2380 945);
DISPLAY 2.276596 (-2380 945);
PAINT GREEN (-2380 945);
DISPLAY INVISIBLE (-2380 945);
FORCEPROP 2 LAST CDS_LIB mstr_standard
J 0
(-2700 1075);
PAINT ORANGE (-2700 1075);
DISPLAY INVISIBLE (-2700 1075);
FORCEPROP 1 LAST PATH I270
J 0
(-2702 1075);
DISPLAY 0.872340 (-2702 1075);
PAINT GREEN (-2702 1075);
DISPLAY INVISIBLE (-2702 1075);
FORCEPROP 1 LAST BODY_TYPE PLUMBING
J 0
(-2650 1025);
DISPLAY 2.276596 (-2650 1025);
PAINT GREEN (-2650 1025);
DISPLAY INVISIBLE (-2650 1025);
FORCEADD TAP..7
(-2750 1275);
FORCEPROP 3 LASTPIN (-2750 1325) SIG_NAME P3E_CPU0_PE1_SS_RXN<4>
J 0
(-2740 1335);
DISPLAY 0.659574 (-2740 1335);
PAINT MONO (-2740 1335);
DISPLAY INVISIBLE (-2740 1335);
FORCEPROP 1 LASTPIN (-2750 1325) BN 4
R 1
J 0
(-2757 1273);
DISPLAY 0.617021 (-2757 1273);
PAINT GREEN (-2757 1273);
FORCEPROP 2 LAST CDS_LIB mstr_standard
J 0
(-2750 1275);
PAINT ORANGE (-2750 1275);
DISPLAY INVISIBLE (-2750 1275);
FORCEPROP 1 LAST PATH I271
J 0
(-2752 1275);
DISPLAY 0.872340 (-2752 1275);
PAINT GREEN (-2752 1275);
DISPLAY INVISIBLE (-2752 1275);
FORCEPROP 1 LAST BODY_TYPE PLUMBING
J 0
(-2700 1275);
DISPLAY 2.276596 (-2700 1275);
PAINT GREEN (-2700 1275);
DISPLAY INVISIBLE (-2700 1275);
FORCEPROP 1 LAST HDL_TAP TRUE
J 0
(-2430 1145);
DISPLAY 2.276596 (-2430 1145);
PAINT GREEN (-2430 1145);
DISPLAY INVISIBLE (-2430 1145);
FORCEADD CAP..1
R 2
(-1900 825);
FORCEPROP 1 LAST LOCATION C2U3
J 2
(-1950 925);
DISPLAY 0.617021 (-1950 925);
PAINT AQUA (-1950 925);
FORCEPROP 1 LAST VALUE 0.22UF
J 2
(-1950 875);
DISPLAY 0.617021 (-1950 875);
PAINT SKYBLUE (-1950 875);
FORCEPROP 1 LAST PACK_TYPE 0402
J 2
(-1950 675);
DISPLAY 0.617021 (-1950 675);
PAINT SKYBLUE (-1950 675);
FORCEPROP 1 LAST PART_NUMBER A36096-155
R 1
J 2
(-1825 725);
DISPLAY 0.617021 (-1825 725);
PAINT BLUE (-1825 725);
FORCEPROP 1 LAST MATERIAL X7R
J 2
(-1950 725);
DISPLAY 0.617021 (-1950 725);
PAINT SKYBLUE (-1950 725);
FORCEPROP 1 LASTPIN (-1900 725) $PN 2
J 2
(-1905 735);
DISPLAY 0.617021 (-1905 735);
PAINT ORANGE (-1905 735);
FORCEPROP 1 LASTPIN (-1900 925) $PN 1
J 2
(-1905 887);
DISPLAY 0.617021 (-1905 887);
PAINT ORANGE (-1905 887);
FORCEPROP 1 LAST VOLTAGE 16V
J 2
(-1950 825);
DISPLAY 0.617021 (-1950 825);
PAINT SKYBLUE (-1950 825);
FORCEPROP 1 LAST TOLERANCE 10%
J 2
(-1950 775);
DISPLAY 0.617021 (-1950 775);
PAINT SKYBLUE (-1950 775);
FORCEPROP 2 LAST CDS_LIB mstr_discrete
J 0
(-1900 825);
PAINT MONO (-1900 825);
DISPLAY INVISIBLE (-1900 825);
FORCEPROP 2 LAST CDS_LOCATION C2U3
J 0
(-1950 975);
DISPLAY 0.617021 (-1950 975);
PAINT AQUA (-1950 975);
DISPLAY INVISIBLE (-1950 975);
FORCEPROP 1 LAST PATH I272
J 2
(-1950 975);
DISPLAY 0.978723 (-1950 975);
PAINT WHITE (-1950 975);
DISPLAY INVISIBLE (-1950 975);
FORCEPROP 2 LAST SEC_TYPE 0402
J 0
(-1950 1025);
DISPLAY 1.021277 (-1950 1025);
PAINT ORANGE (-1950 1025);
DISPLAY INVISIBLE (-1950 1025);
FORCEPROP 2 LAST SEC 1
J 0
(-1950 1050);
DISPLAY 0.680851 (-1950 1050);
PAINT MONO (-1950 1050);
DISPLAY INVISIBLE (-1950 1050);
FORCEADD TAP..7
(-1900 275);
FORCEPROP 3 LASTPIN (-1900 325) SIG_NAME P3E_CPU0_PE1_SS_RXP<0>
J 0
(-1890 335);
DISPLAY 0.659574 (-1890 335);
PAINT MONO (-1890 335);
DISPLAY INVISIBLE (-1890 335);
FORCEPROP 1 LASTPIN (-1900 325) BN 0
R 1
J 0
(-1907 273);
DISPLAY 0.617021 (-1907 273);
PAINT GREEN (-1907 273);
FORCEPROP 2 LAST CDS_LIB mstr_standard
J 0
(-1900 275);
PAINT ORANGE (-1900 275);
DISPLAY INVISIBLE (-1900 275);
FORCEPROP 1 LAST BODY_TYPE PLUMBING
J 0
(-1850 275);
DISPLAY 2.276596 (-1850 275);
PAINT GREEN (-1850 275);
DISPLAY INVISIBLE (-1850 275);
FORCEPROP 1 LAST PATH I273
J 0
(-1902 275);
DISPLAY 0.872340 (-1902 275);
PAINT GREEN (-1902 275);
DISPLAY INVISIBLE (-1902 275);
FORCEPROP 1 LAST HDL_TAP TRUE
J 0
(-1580 145);
DISPLAY 2.276596 (-1580 145);
PAINT GREEN (-1580 145);
DISPLAY INVISIBLE (-1580 145);
FORCEADD CAP..1
R 2
(-2100 525);
FORCEPROP 1 LAST MATERIAL X7R
J 2
(-2150 425);
DISPLAY 0.617021 (-2150 425);
PAINT SKYBLUE (-2150 425);
FORCEPROP 1 LAST PACK_TYPE 0402
J 2
(-2150 375);
DISPLAY 0.617021 (-2150 375);
PAINT SKYBLUE (-2150 375);
FORCEPROP 1 LAST TOLERANCE 10%
J 2
(-2150 475);
DISPLAY 0.617021 (-2150 475);
PAINT SKYBLUE (-2150 475);
FORCEPROP 1 LASTPIN (-2100 425) $PN 2
J 2
(-2105 435);
DISPLAY 0.617021 (-2105 435);
PAINT ORANGE (-2105 435);
FORCEPROP 1 LAST VALUE 0.22UF
J 2
(-2150 575);
DISPLAY 0.617021 (-2150 575);
PAINT SKYBLUE (-2150 575);
FORCEPROP 1 LAST VOLTAGE 16V
J 2
(-2150 525);
DISPLAY 0.617021 (-2150 525);
PAINT SKYBLUE (-2150 525);
FORCEPROP 1 LASTPIN (-2100 625) $PN 1
J 2
(-2105 587);
DISPLAY 0.617021 (-2105 587);
PAINT ORANGE (-2105 587);
FORCEPROP 1 LAST LOCATION C2U5
J 2
(-2150 625);
DISPLAY 0.617021 (-2150 625);
PAINT AQUA (-2150 625);
FORCEPROP 1 LAST PART_NUMBER A36096-155
R 1
J 2
(-2125 925);
DISPLAY 0.617021 (-2125 925);
PAINT BLUE (-2125 925);
FORCEPROP 2 LAST CDS_LIB mstr_discrete
J 0
(-2100 525);
PAINT MONO (-2100 525);
DISPLAY INVISIBLE (-2100 525);
FORCEPROP 2 LAST SEC_TYPE 0402
J 0
(-2150 725);
DISPLAY 1.021277 (-2150 725);
PAINT ORANGE (-2150 725);
DISPLAY INVISIBLE (-2150 725);
FORCEPROP 2 LAST CDS_LOCATION C2U5
J 0
(-2150 675);
DISPLAY 0.617021 (-2150 675);
PAINT AQUA (-2150 675);
DISPLAY INVISIBLE (-2150 675);
FORCEPROP 1 LAST PATH I274
J 2
(-2150 675);
DISPLAY 0.978723 (-2150 675);
PAINT WHITE (-2150 675);
DISPLAY INVISIBLE (-2150 675);
FORCEPROP 2 LAST SEC 1
J 0
(-2150 750);
DISPLAY 0.680851 (-2150 750);
PAINT MONO (-2150 750);
DISPLAY INVISIBLE (-2150 750);
FORCEADD TAP..7
(-2100 275);
FORCEPROP 3 LASTPIN (-2100 325) SIG_NAME P3E_CPU0_PE1_SS_RXP<1>
J 0
(-2090 335);
DISPLAY 0.659574 (-2090 335);
PAINT MONO (-2090 335);
DISPLAY INVISIBLE (-2090 335);
FORCEPROP 1 LASTPIN (-2100 325) BN 1
R 1
J 0
(-2107 273);
DISPLAY 0.617021 (-2107 273);
PAINT GREEN (-2107 273);
FORCEPROP 1 LAST BODY_TYPE PLUMBING
J 0
(-2050 275);
DISPLAY 2.276596 (-2050 275);
PAINT GREEN (-2050 275);
DISPLAY INVISIBLE (-2050 275);
FORCEPROP 2 LAST CDS_LIB mstr_standard
J 0
(-2100 275);
PAINT ORANGE (-2100 275);
DISPLAY INVISIBLE (-2100 275);
FORCEPROP 1 LAST PATH I275
J 0
(-2102 275);
DISPLAY 0.872340 (-2102 275);
PAINT GREEN (-2102 275);
DISPLAY INVISIBLE (-2102 275);
FORCEPROP 1 LAST HDL_TAP TRUE
J 0
(-1780 145);
DISPLAY 2.276596 (-1780 145);
PAINT GREEN (-1780 145);
DISPLAY INVISIBLE (-1780 145);
FORCEADD TAP..7
(-2300 275);
FORCEPROP 3 LASTPIN (-2300 325) SIG_NAME P3E_CPU0_PE1_SS_RXP<2>
J 0
(-2290 335);
DISPLAY 0.659574 (-2290 335);
PAINT MONO (-2290 335);
DISPLAY INVISIBLE (-2290 335);
FORCEPROP 1 LASTPIN (-2300 325) BN 2
R 1
J 0
(-2307 273);
DISPLAY 0.617021 (-2307 273);
PAINT GREEN (-2307 273);
FORCEPROP 1 LAST PATH I276
J 0
(-2302 275);
DISPLAY 0.872340 (-2302 275);
PAINT GREEN (-2302 275);
DISPLAY INVISIBLE (-2302 275);
FORCEPROP 1 LAST BODY_TYPE PLUMBING
J 0
(-2250 275);
DISPLAY 2.276596 (-2250 275);
PAINT GREEN (-2250 275);
DISPLAY INVISIBLE (-2250 275);
FORCEPROP 2 LAST CDS_LIB mstr_standard
J 0
(-2300 275);
PAINT ORANGE (-2300 275);
DISPLAY INVISIBLE (-2300 275);
FORCEPROP 1 LAST HDL_TAP TRUE
J 0
(-1980 145);
DISPLAY 2.276596 (-1980 145);
PAINT GREEN (-1980 145);
DISPLAY INVISIBLE (-1980 145);
FORCEADD CAP..1
R 2
(-2300 825);
FORCEPROP 1 LAST PART_NUMBER A36096-155
R 1
J 2
(-2300 600);
DISPLAY 0.617021 (-2300 600);
PAINT BLUE (-2300 600);
FORCEPROP 1 LAST MATERIAL X7R
J 2
(-2350 725);
DISPLAY 0.617021 (-2350 725);
PAINT SKYBLUE (-2350 725);
FORCEPROP 1 LAST PACK_TYPE 0402
J 2
(-2350 675);
DISPLAY 0.617021 (-2350 675);
PAINT SKYBLUE (-2350 675);
FORCEPROP 1 LASTPIN (-2300 725) $PN 2
J 2
(-2305 735);
DISPLAY 0.617021 (-2305 735);
PAINT ORANGE (-2305 735);
FORCEPROP 1 LAST VALUE 0.22UF
J 2
(-2350 875);
DISPLAY 0.617021 (-2350 875);
PAINT SKYBLUE (-2350 875);
FORCEPROP 1 LASTPIN (-2300 925) $PN 1
J 2
(-2305 887);
DISPLAY 0.617021 (-2305 887);
PAINT ORANGE (-2305 887);
FORCEPROP 1 LAST VOLTAGE 16V
J 2
(-2350 825);
DISPLAY 0.617021 (-2350 825);
PAINT SKYBLUE (-2350 825);
FORCEPROP 1 LAST LOCATION C2U7
J 2
(-2350 925);
DISPLAY 0.617021 (-2350 925);
PAINT AQUA (-2350 925);
FORCEPROP 1 LAST TOLERANCE 10%
J 2
(-2350 775);
DISPLAY 0.617021 (-2350 775);
PAINT SKYBLUE (-2350 775);
FORCEPROP 1 LAST PATH I277
J 2
(-2350 975);
DISPLAY 0.978723 (-2350 975);
PAINT WHITE (-2350 975);
DISPLAY INVISIBLE (-2350 975);
FORCEPROP 2 LAST CDS_LOCATION C2U7
J 0
(-2350 975);
DISPLAY 0.617021 (-2350 975);
PAINT AQUA (-2350 975);
DISPLAY INVISIBLE (-2350 975);
FORCEPROP 2 LAST CDS_LIB mstr_discrete
J 0
(-2300 825);
PAINT MONO (-2300 825);
DISPLAY INVISIBLE (-2300 825);
FORCEPROP 2 LAST SEC 1
J 0
(-2350 1050);
DISPLAY 0.680851 (-2350 1050);
PAINT MONO (-2350 1050);
DISPLAY INVISIBLE (-2350 1050);
FORCEPROP 2 LAST SEC_TYPE 0402
J 0
(-2350 1025);
DISPLAY 1.021277 (-2350 1025);
PAINT ORANGE (-2350 1025);
DISPLAY INVISIBLE (-2350 1025);
FORCEADD CAP..1
R 2
(-2700 825);
FORCEPROP 1 LAST PART_NUMBER A36096-155
R 1
J 2
(-2725 625);
DISPLAY 0.617021 (-2725 625);
PAINT BLUE (-2725 625);
FORCEPROP 1 LAST LOCATION C2U11
J 2
(-2750 925);
DISPLAY 0.617021 (-2750 925);
PAINT AQUA (-2750 925);
FORCEPROP 1 LAST PACK_TYPE 0402
J 2
(-2750 675);
DISPLAY 0.617021 (-2750 675);
PAINT SKYBLUE (-2750 675);
FORCEPROP 1 LAST VALUE 0.22UF
J 2
(-2750 875);
DISPLAY 0.617021 (-2750 875);
PAINT SKYBLUE (-2750 875);
FORCEPROP 1 LAST MATERIAL X7R
J 2
(-2750 725);
DISPLAY 0.617021 (-2750 725);
PAINT SKYBLUE (-2750 725);
FORCEPROP 1 LAST VOLTAGE 16V
J 2
(-2750 825);
DISPLAY 0.617021 (-2750 825);
PAINT SKYBLUE (-2750 825);
FORCEPROP 1 LAST TOLERANCE 10%
J 2
(-2750 775);
DISPLAY 0.617021 (-2750 775);
PAINT SKYBLUE (-2750 775);
FORCEPROP 1 LASTPIN (-2700 725) $PN 2
J 2
(-2705 735);
DISPLAY 0.617021 (-2705 735);
PAINT ORANGE (-2705 735);
FORCEPROP 1 LASTPIN (-2700 925) $PN 1
J 2
(-2705 887);
DISPLAY 0.617021 (-2705 887);
PAINT ORANGE (-2705 887);
FORCEPROP 1 LAST PATH I278
J 2
(-2750 975);
DISPLAY 0.978723 (-2750 975);
PAINT WHITE (-2750 975);
DISPLAY INVISIBLE (-2750 975);
FORCEPROP 2 LAST CDS_LOCATION C2U11
J 0
(-2750 975);
DISPLAY 0.617021 (-2750 975);
PAINT AQUA (-2750 975);
DISPLAY INVISIBLE (-2750 975);
FORCEPROP 2 LAST CDS_LIB mstr_discrete
J 0
(-2700 825);
PAINT MONO (-2700 825);
DISPLAY INVISIBLE (-2700 825);
FORCEPROP 2 LAST SEC_TYPE 0402
J 0
(-2750 1025);
DISPLAY 1.021277 (-2750 1025);
PAINT ORANGE (-2750 1025);
DISPLAY INVISIBLE (-2750 1025);
FORCEPROP 2 LAST SEC 1
J 0
(-2750 1050);
DISPLAY 0.680851 (-2750 1050);
PAINT MONO (-2750 1050);
DISPLAY INVISIBLE (-2750 1050);
FORCEADD CAP..1
R 2
(-2500 525);
FORCEPROP 1 LAST VOLTAGE 16V
J 2
(-2550 525);
DISPLAY 0.617021 (-2550 525);
PAINT SKYBLUE (-2550 525);
FORCEPROP 1 LAST LOCATION C2U9
J 2
(-2550 625);
DISPLAY 0.617021 (-2550 625);
PAINT AQUA (-2550 625);
FORCEPROP 1 LAST PACK_TYPE 0402
J 2
(-2550 375);
DISPLAY 0.617021 (-2550 375);
PAINT SKYBLUE (-2550 375);
FORCEPROP 1 LAST VALUE 0.22UF
J 2
(-2550 575);
DISPLAY 0.617021 (-2550 575);
PAINT SKYBLUE (-2550 575);
FORCEPROP 1 LAST MATERIAL X7R
J 2
(-2550 425);
DISPLAY 0.617021 (-2550 425);
PAINT SKYBLUE (-2550 425);
FORCEPROP 1 LAST TOLERANCE 10%
J 2
(-2550 475);
DISPLAY 0.617021 (-2550 475);
PAINT SKYBLUE (-2550 475);
FORCEPROP 1 LASTPIN (-2500 425) $PN 2
J 2
(-2505 435);
DISPLAY 0.617021 (-2505 435);
PAINT ORANGE (-2505 435);
FORCEPROP 1 LASTPIN (-2500 625) $PN 1
J 2
(-2505 587);
DISPLAY 0.617021 (-2505 587);
PAINT ORANGE (-2505 587);
FORCEPROP 1 LAST PART_NUMBER A36096-155
R 1
J 2
(-2525 925);
DISPLAY 0.617021 (-2525 925);
PAINT BLUE (-2525 925);
FORCEPROP 1 LAST PATH I279
J 2
(-2550 675);
DISPLAY 0.978723 (-2550 675);
PAINT WHITE (-2550 675);
DISPLAY INVISIBLE (-2550 675);
FORCEPROP 2 LAST CDS_LOCATION C2U9
J 0
(-2550 675);
DISPLAY 0.617021 (-2550 675);
PAINT AQUA (-2550 675);
DISPLAY INVISIBLE (-2550 675);
FORCEPROP 2 LAST CDS_LIB mstr_discrete
J 0
(-2500 525);
PAINT MONO (-2500 525);
DISPLAY INVISIBLE (-2500 525);
FORCEPROP 2 LAST SEC_TYPE 0402
J 0
(-2550 725);
DISPLAY 1.021277 (-2550 725);
PAINT ORANGE (-2550 725);
DISPLAY INVISIBLE (-2550 725);
FORCEPROP 2 LAST SEC 1
J 0
(-2550 750);
DISPLAY 0.680851 (-2550 750);
PAINT MONO (-2550 750);
DISPLAY INVISIBLE (-2550 750);
FORCEADD TAP..7
(-2500 275);
FORCEPROP 3 LASTPIN (-2500 325) SIG_NAME P3E_CPU0_PE1_SS_RXP<3>
J 0
(-2490 335);
DISPLAY 0.659574 (-2490 335);
PAINT MONO (-2490 335);
DISPLAY INVISIBLE (-2490 335);
FORCEPROP 1 LASTPIN (-2500 325) BN 3
R 1
J 0
(-2507 273);
DISPLAY 0.617021 (-2507 273);
PAINT GREEN (-2507 273);
FORCEPROP 2 LAST CDS_LIB mstr_standard
J 0
(-2500 275);
PAINT ORANGE (-2500 275);
DISPLAY INVISIBLE (-2500 275);
FORCEPROP 1 LAST BODY_TYPE PLUMBING
J 0
(-2450 275);
DISPLAY 2.276596 (-2450 275);
PAINT GREEN (-2450 275);
DISPLAY INVISIBLE (-2450 275);
FORCEPROP 1 LAST PATH I280
J 0
(-2502 275);
DISPLAY 0.872340 (-2502 275);
PAINT GREEN (-2502 275);
DISPLAY INVISIBLE (-2502 275);
FORCEPROP 1 LAST HDL_TAP TRUE
J 0
(-2180 145);
DISPLAY 2.276596 (-2180 145);
PAINT GREEN (-2180 145);
DISPLAY INVISIBLE (-2180 145);
FORCEADD TAP..7
(-2700 275);
FORCEPROP 3 LASTPIN (-2700 325) SIG_NAME P3E_CPU0_PE1_SS_RXP<4>
J 0
(-2690 335);
DISPLAY 0.659574 (-2690 335);
PAINT MONO (-2690 335);
DISPLAY INVISIBLE (-2690 335);
FORCEPROP 1 LASTPIN (-2700 325) BN 4
R 1
J 0
(-2707 273);
DISPLAY 0.617021 (-2707 273);
PAINT GREEN (-2707 273);
FORCEPROP 2 LAST CDS_LIB mstr_standard
J 0
(-2700 275);
PAINT ORANGE (-2700 275);
DISPLAY INVISIBLE (-2700 275);
FORCEPROP 1 LAST BODY_TYPE PLUMBING
J 0
(-2650 275);
DISPLAY 2.276596 (-2650 275);
PAINT GREEN (-2650 275);
DISPLAY INVISIBLE (-2650 275);
FORCEPROP 1 LAST PATH I281
J 0
(-2702 275);
DISPLAY 0.872340 (-2702 275);
PAINT GREEN (-2702 275);
DISPLAY INVISIBLE (-2702 275);
FORCEPROP 1 LAST HDL_TAP TRUE
J 0
(-2380 145);
DISPLAY 2.276596 (-2380 145);
PAINT GREEN (-2380 145);
DISPLAY INVISIBLE (-2380 145);
FORCEADD TAP..3
(-2950 2075);
FORCEPROP 3 LASTPIN (-2950 2025) SIG_NAME P3E_CPU0_PE1_PCH_RXN<5>
J 0
(-2940 2035);
DISPLAY 0.659574 (-2940 2035);
PAINT MONO (-2940 2035);
DISPLAY INVISIBLE (-2940 2035);
FORCEPROP 1 LASTPIN (-2950 2025) BN 5
R 1
J 0
(-2957 2013);
DISPLAY 0.617021 (-2957 2013);
PAINT GREEN (-2957 2013);
FORCEPROP 1 LAST HDL_TAP TRUE
J 0
(-2630 1945);
DISPLAY 2.276596 (-2630 1945);
PAINT GREEN (-2630 1945);
DISPLAY INVISIBLE (-2630 1945);
FORCEPROP 1 LAST BODY_TYPE PLUMBING
J 0
(-2900 2025);
DISPLAY 2.276596 (-2900 2025);
PAINT GREEN (-2900 2025);
DISPLAY INVISIBLE (-2900 2025);
FORCEPROP 2 LAST CDS_LIB mstr_standard
J 0
(-2950 2075);
PAINT ORANGE (-2950 2075);
DISPLAY INVISIBLE (-2950 2075);
FORCEPROP 1 LAST PATH I282
J 0
(-2952 2075);
DISPLAY 0.872340 (-2952 2075);
PAINT GREEN (-2952 2075);
DISPLAY INVISIBLE (-2952 2075);
FORCEADD TAP..3
(-3150 2075);
FORCEPROP 3 LASTPIN (-3150 2025) SIG_NAME P3E_CPU0_PE1_PCH_RXN<6>
J 0
(-3140 2035);
DISPLAY 0.659574 (-3140 2035);
PAINT MONO (-3140 2035);
DISPLAY INVISIBLE (-3140 2035);
FORCEPROP 1 LASTPIN (-3150 2025) BN 6
R 1
J 0
(-3157 2013);
DISPLAY 0.617021 (-3157 2013);
PAINT GREEN (-3157 2013);
FORCEPROP 1 LAST HDL_TAP TRUE
J 0
(-2830 1945);
DISPLAY 2.276596 (-2830 1945);
PAINT GREEN (-2830 1945);
DISPLAY INVISIBLE (-2830 1945);
FORCEPROP 1 LAST BODY_TYPE PLUMBING
J 0
(-3100 2025);
DISPLAY 2.276596 (-3100 2025);
PAINT GREEN (-3100 2025);
DISPLAY INVISIBLE (-3100 2025);
FORCEPROP 2 LAST CDS_LIB mstr_standard
J 0
(-3150 2075);
PAINT ORANGE (-3150 2075);
DISPLAY INVISIBLE (-3150 2075);
FORCEPROP 1 LAST PATH I283
J 0
(-3152 2075);
DISPLAY 0.872340 (-3152 2075);
PAINT GREEN (-3152 2075);
DISPLAY INVISIBLE (-3152 2075);
FORCEADD TAP..3
(-3350 2075);
FORCEPROP 3 LASTPIN (-3350 2025) SIG_NAME P3E_CPU0_PE1_PCH_RXN<7>
J 0
(-3340 2035);
DISPLAY 0.659574 (-3340 2035);
PAINT MONO (-3340 2035);
DISPLAY INVISIBLE (-3340 2035);
FORCEPROP 1 LASTPIN (-3350 2025) BN 7
R 1
J 0
(-3357 2013);
DISPLAY 0.617021 (-3357 2013);
PAINT GREEN (-3357 2013);
FORCEPROP 1 LAST HDL_TAP TRUE
J 0
(-3030 1945);
DISPLAY 2.276596 (-3030 1945);
PAINT GREEN (-3030 1945);
DISPLAY INVISIBLE (-3030 1945);
FORCEPROP 1 LAST BODY_TYPE PLUMBING
J 0
(-3300 2025);
DISPLAY 2.276596 (-3300 2025);
PAINT GREEN (-3300 2025);
DISPLAY INVISIBLE (-3300 2025);
FORCEPROP 2 LAST CDS_LIB mstr_standard
J 0
(-3350 2075);
PAINT ORANGE (-3350 2075);
DISPLAY INVISIBLE (-3350 2075);
FORCEPROP 1 LAST PATH I284
J 0
(-3352 2075);
DISPLAY 0.872340 (-3352 2075);
PAINT GREEN (-3352 2075);
DISPLAY INVISIBLE (-3352 2075);
FORCEADD OFFPAGE..1
(-3525 2125);
FORCEPROP 2 LAST $XR0 117 
J 0
(-3807 2125);
DISPLAY 0.638298 (-3807 2125);
PAINT MONO (-3807 2125);
FORCEPROP 1 LAST OFFPAGE TRUE
J 0
(-3205 1995);
PAINT GREEN (-3205 1995);
DISPLAY INVISIBLE (-3205 1995);
FORCEPROP 1 LAST COMMENT_BODY TRUE
J 0
(-3405 2025);
DISPLAY 2.276596 (-3405 2025);
PAINT GREEN (-3405 2025);
DISPLAY INVISIBLE (-3405 2025);
FORCEPROP 2 LAST PATH I285
J 0
(-3475 2200);
DISPLAY 1.021277 (-3475 2200);
PAINT ORANGE (-3475 2200);
DISPLAY INVISIBLE (-3475 2200);
FORCEPROP 2 LAST CDS_LIB mstr_standard
J 0
(-3525 2125);
PAINT ORANGE (-3525 2125);
DISPLAY INVISIBLE (-3525 2125);
FORCEADD CAP..1
R 2
(-3150 1825);
FORCEPROP 1 LAST PART_NUMBER A36096-155
R 1
J 2
(-3175 1650);
DISPLAY 0.617021 (-3175 1650);
PAINT BLUE (-3175 1650);
FORCEPROP 1 LAST VALUE 0.22UF
J 2
(-3200 1875);
DISPLAY 0.617021 (-3200 1875);
PAINT SKYBLUE (-3200 1875);
FORCEPROP 1 LAST LOCATION C2U16
J 2
(-3200 1925);
DISPLAY 0.617021 (-3200 1925);
PAINT AQUA (-3200 1925);
FORCEPROP 1 LAST PACK_TYPE 0402
J 2
(-3200 1675);
DISPLAY 0.617021 (-3200 1675);
PAINT SKYBLUE (-3200 1675);
FORCEPROP 1 LAST MATERIAL X7R
J 2
(-3200 1725);
DISPLAY 0.617021 (-3200 1725);
PAINT SKYBLUE (-3200 1725);
FORCEPROP 1 LASTPIN (-3150 1725) $PN 2
J 2
(-3155 1735);
DISPLAY 0.617021 (-3155 1735);
PAINT ORANGE (-3155 1735);
FORCEPROP 1 LAST TOLERANCE 10%
J 2
(-3200 1775);
DISPLAY 0.617021 (-3200 1775);
PAINT SKYBLUE (-3200 1775);
FORCEPROP 1 LAST VOLTAGE 16V
J 2
(-3200 1825);
DISPLAY 0.617021 (-3200 1825);
PAINT SKYBLUE (-3200 1825);
FORCEPROP 1 LASTPIN (-3150 1925) $PN 1
J 2
(-3155 1887);
DISPLAY 0.617021 (-3155 1887);
PAINT ORANGE (-3155 1887);
FORCEPROP 1 LAST PATH I286
J 2
(-3200 1975);
DISPLAY 0.978723 (-3200 1975);
PAINT WHITE (-3200 1975);
DISPLAY INVISIBLE (-3200 1975);
FORCEPROP 2 LAST CDS_LOCATION C2U16
J 0
(-3200 1975);
DISPLAY 0.617021 (-3200 1975);
PAINT AQUA (-3200 1975);
DISPLAY INVISIBLE (-3200 1975);
FORCEPROP 2 LAST CDS_LIB mstr_discrete
J 0
(-3150 1825);
PAINT MONO (-3150 1825);
DISPLAY INVISIBLE (-3150 1825);
FORCEPROP 2 LAST SEC_TYPE 0402
J 0
(-3200 2025);
DISPLAY 1.021277 (-3200 2025);
PAINT ORANGE (-3200 2025);
DISPLAY INVISIBLE (-3200 2025);
FORCEPROP 2 LAST SEC 1
J 0
(-3200 2050);
DISPLAY 0.680851 (-3200 2050);
PAINT MONO (-3200 2050);
DISPLAY INVISIBLE (-3200 2050);
FORCEADD CAP..1
R 2
(-2950 1525);
FORCEPROP 1 LAST TOLERANCE 10%
J 2
(-3000 1475);
DISPLAY 0.617021 (-3000 1475);
PAINT SKYBLUE (-3000 1475);
FORCEPROP 1 LAST MATERIAL X7R
J 2
(-3000 1425);
DISPLAY 0.617021 (-3000 1425);
PAINT SKYBLUE (-3000 1425);
FORCEPROP 1 LAST PACK_TYPE 0402
J 2
(-3000 1375);
DISPLAY 0.617021 (-3000 1375);
PAINT SKYBLUE (-3000 1375);
FORCEPROP 1 LAST LOCATION C2U14
J 2
(-3000 1625);
DISPLAY 0.617021 (-3000 1625);
PAINT AQUA (-3000 1625);
FORCEPROP 1 LAST VALUE 0.22UF
J 2
(-3000 1575);
DISPLAY 0.617021 (-3000 1575);
PAINT SKYBLUE (-3000 1575);
FORCEPROP 1 LAST VOLTAGE 16V
J 2
(-3000 1525);
DISPLAY 0.617021 (-3000 1525);
PAINT SKYBLUE (-3000 1525);
FORCEPROP 1 LASTPIN (-2950 1425) $PN 2
J 2
(-2955 1435);
DISPLAY 0.617021 (-2955 1435);
PAINT ORANGE (-2955 1435);
FORCEPROP 1 LASTPIN (-2950 1625) $PN 1
J 2
(-2955 1587);
DISPLAY 0.617021 (-2955 1587);
PAINT ORANGE (-2955 1587);
FORCEPROP 1 LAST PART_NUMBER A36096-155
R 1
J 2
(-2975 1950);
DISPLAY 0.617021 (-2975 1950);
PAINT BLUE (-2975 1950);
FORCEPROP 2 LAST CDS_LIB mstr_discrete
J 0
(-2950 1525);
PAINT MONO (-2950 1525);
DISPLAY INVISIBLE (-2950 1525);
FORCEPROP 1 LAST PATH I287
J 2
(-3000 1675);
DISPLAY 0.978723 (-3000 1675);
PAINT WHITE (-3000 1675);
DISPLAY INVISIBLE (-3000 1675);
FORCEPROP 2 LAST CDS_LOCATION C2U14
J 0
(-3000 1675);
DISPLAY 0.617021 (-3000 1675);
PAINT AQUA (-3000 1675);
DISPLAY INVISIBLE (-3000 1675);
FORCEPROP 2 LAST SEC 1
J 0
(-3000 1750);
DISPLAY 0.680851 (-3000 1750);
PAINT MONO (-3000 1750);
DISPLAY INVISIBLE (-3000 1750);
FORCEPROP 2 LAST SEC_TYPE 0402
J 0
(-3000 1725);
DISPLAY 1.021277 (-3000 1725);
PAINT ORANGE (-3000 1725);
DISPLAY INVISIBLE (-3000 1725);
FORCEADD TAP..3
(-2900 1075);
FORCEPROP 3 LASTPIN (-2900 1025) SIG_NAME P3E_CPU0_PE1_PCH_RXP<5>
J 0
(-2890 1035);
DISPLAY 0.659574 (-2890 1035);
PAINT MONO (-2890 1035);
DISPLAY INVISIBLE (-2890 1035);
FORCEPROP 1 LASTPIN (-2900 1025) BN 5
R 1
J 0
(-2907 1013);
DISPLAY 0.617021 (-2907 1013);
PAINT GREEN (-2907 1013);
FORCEPROP 1 LAST HDL_TAP TRUE
J 0
(-2580 945);
DISPLAY 2.276596 (-2580 945);
PAINT GREEN (-2580 945);
DISPLAY INVISIBLE (-2580 945);
FORCEPROP 1 LAST PATH I288
J 0
(-2902 1075);
DISPLAY 0.872340 (-2902 1075);
PAINT GREEN (-2902 1075);
DISPLAY INVISIBLE (-2902 1075);
FORCEPROP 1 LAST BODY_TYPE PLUMBING
J 0
(-2850 1025);
DISPLAY 2.276596 (-2850 1025);
PAINT GREEN (-2850 1025);
DISPLAY INVISIBLE (-2850 1025);
FORCEPROP 2 LAST CDS_LIB mstr_standard
J 0
(-2900 1075);
PAINT ORANGE (-2900 1075);
DISPLAY INVISIBLE (-2900 1075);
FORCEADD TAP..7
(-2950 1275);
FORCEPROP 3 LASTPIN (-2950 1325) SIG_NAME P3E_CPU0_PE1_SS_RXN<5>
J 0
(-2940 1335);
DISPLAY 0.659574 (-2940 1335);
PAINT MONO (-2940 1335);
DISPLAY INVISIBLE (-2940 1335);
FORCEPROP 1 LASTPIN (-2950 1325) BN 5
R 1
J 0
(-2957 1273);
DISPLAY 0.617021 (-2957 1273);
PAINT GREEN (-2957 1273);
FORCEPROP 2 LAST CDS_LIB mstr_standard
J 0
(-2950 1275);
PAINT ORANGE (-2950 1275);
DISPLAY INVISIBLE (-2950 1275);
FORCEPROP 1 LAST BODY_TYPE PLUMBING
J 0
(-2900 1275);
DISPLAY 2.276596 (-2900 1275);
PAINT GREEN (-2900 1275);
DISPLAY INVISIBLE (-2900 1275);
FORCEPROP 1 LAST PATH I289
J 0
(-2952 1275);
DISPLAY 0.872340 (-2952 1275);
PAINT GREEN (-2952 1275);
DISPLAY INVISIBLE (-2952 1275);
FORCEPROP 1 LAST HDL_TAP TRUE
J 0
(-2630 1145);
DISPLAY 2.276596 (-2630 1145);
PAINT GREEN (-2630 1145);
DISPLAY INVISIBLE (-2630 1145);
FORCEADD TAP..7
(-3150 1275);
FORCEPROP 3 LASTPIN (-3150 1325) SIG_NAME P3E_CPU0_PE1_SS_RXN<6>
J 0
(-3140 1335);
DISPLAY 0.659574 (-3140 1335);
PAINT MONO (-3140 1335);
DISPLAY INVISIBLE (-3140 1335);
FORCEPROP 1 LASTPIN (-3150 1325) BN 6
R 1
J 0
(-3157 1273);
DISPLAY 0.617021 (-3157 1273);
PAINT GREEN (-3157 1273);
FORCEPROP 2 LAST CDS_LIB mstr_standard
J 0
(-3150 1275);
PAINT ORANGE (-3150 1275);
DISPLAY INVISIBLE (-3150 1275);
FORCEPROP 1 LAST BODY_TYPE PLUMBING
J 0
(-3100 1275);
DISPLAY 2.276596 (-3100 1275);
PAINT GREEN (-3100 1275);
DISPLAY INVISIBLE (-3100 1275);
FORCEPROP 1 LAST PATH I290
J 0
(-3152 1275);
DISPLAY 0.872340 (-3152 1275);
PAINT GREEN (-3152 1275);
DISPLAY INVISIBLE (-3152 1275);
FORCEPROP 1 LAST HDL_TAP TRUE
J 0
(-2830 1145);
DISPLAY 2.276596 (-2830 1145);
PAINT GREEN (-2830 1145);
DISPLAY INVISIBLE (-2830 1145);
FORCEADD TAP..3
(-3100 1075);
FORCEPROP 3 LASTPIN (-3100 1025) SIG_NAME P3E_CPU0_PE1_PCH_RXP<6>
J 0
(-3090 1035);
DISPLAY 0.659574 (-3090 1035);
PAINT MONO (-3090 1035);
DISPLAY INVISIBLE (-3090 1035);
FORCEPROP 1 LASTPIN (-3100 1025) BN 6
R 1
J 0
(-3107 1013);
DISPLAY 0.617021 (-3107 1013);
PAINT GREEN (-3107 1013);
FORCEPROP 1 LAST PATH I291
J 0
(-3102 1075);
DISPLAY 0.872340 (-3102 1075);
PAINT GREEN (-3102 1075);
DISPLAY INVISIBLE (-3102 1075);
FORCEPROP 2 LAST CDS_LIB mstr_standard
J 0
(-3100 1075);
PAINT ORANGE (-3100 1075);
DISPLAY INVISIBLE (-3100 1075);
FORCEPROP 1 LAST HDL_TAP TRUE
J 0
(-2780 945);
DISPLAY 2.276596 (-2780 945);
PAINT GREEN (-2780 945);
DISPLAY INVISIBLE (-2780 945);
FORCEPROP 1 LAST BODY_TYPE PLUMBING
J 0
(-3050 1025);
DISPLAY 2.276596 (-3050 1025);
PAINT GREEN (-3050 1025);
DISPLAY INVISIBLE (-3050 1025);
FORCEADD TAP..7
(-3350 1275);
FORCEPROP 3 LASTPIN (-3350 1325) SIG_NAME P3E_CPU0_PE1_SS_RXN<7>
J 0
(-3340 1335);
DISPLAY 0.659574 (-3340 1335);
PAINT MONO (-3340 1335);
DISPLAY INVISIBLE (-3340 1335);
FORCEPROP 1 LASTPIN (-3350 1325) BN 7
R 1
J 0
(-3357 1273);
DISPLAY 0.617021 (-3357 1273);
PAINT GREEN (-3357 1273);
FORCEPROP 2 LAST CDS_LIB mstr_standard
J 0
(-3350 1275);
PAINT ORANGE (-3350 1275);
DISPLAY INVISIBLE (-3350 1275);
FORCEPROP 1 LAST PATH I292
J 0
(-3352 1275);
DISPLAY 0.872340 (-3352 1275);
PAINT GREEN (-3352 1275);
DISPLAY INVISIBLE (-3352 1275);
FORCEPROP 1 LAST BODY_TYPE PLUMBING
J 0
(-3300 1275);
DISPLAY 2.276596 (-3300 1275);
PAINT GREEN (-3300 1275);
DISPLAY INVISIBLE (-3300 1275);
FORCEPROP 1 LAST HDL_TAP TRUE
J 0
(-3030 1145);
DISPLAY 2.276596 (-3030 1145);
PAINT GREEN (-3030 1145);
DISPLAY INVISIBLE (-3030 1145);
FORCEADD TAP..3
(-3300 1075);
FORCEPROP 3 LASTPIN (-3300 1025) SIG_NAME P3E_CPU0_PE1_PCH_RXP<7>
J 0
(-3290 1035);
DISPLAY 0.659574 (-3290 1035);
PAINT MONO (-3290 1035);
DISPLAY INVISIBLE (-3290 1035);
FORCEPROP 1 LASTPIN (-3300 1025) BN 7
R 1
J 0
(-3307 1013);
DISPLAY 0.617021 (-3307 1013);
PAINT GREEN (-3307 1013);
FORCEPROP 2 LAST CDS_LIB mstr_standard
J 0
(-3300 1075);
PAINT ORANGE (-3300 1075);
DISPLAY INVISIBLE (-3300 1075);
FORCEPROP 1 LAST BODY_TYPE PLUMBING
J 0
(-3250 1025);
DISPLAY 2.276596 (-3250 1025);
PAINT GREEN (-3250 1025);
DISPLAY INVISIBLE (-3250 1025);
FORCEPROP 1 LAST PATH I293
J 0
(-3302 1075);
DISPLAY 0.872340 (-3302 1075);
PAINT GREEN (-3302 1075);
DISPLAY INVISIBLE (-3302 1075);
FORCEPROP 1 LAST HDL_TAP TRUE
J 0
(-2980 945);
DISPLAY 2.276596 (-2980 945);
PAINT GREEN (-2980 945);
DISPLAY INVISIBLE (-2980 945);
FORCEADD CAP..1
R 2
(-3350 1525);
FORCEPROP 1 LAST PART_NUMBER A36096-155
J 2
(-3400 1375);
DISPLAY 0.617021 (-3400 1375);
PAINT BLUE (-3400 1375);
FORCEPROP 1 LAST PACK_TYPE 0402
J 2
(-3400 1325);
DISPLAY 0.617021 (-3400 1325);
PAINT SKYBLUE (-3400 1325);
FORCEPROP 1 LASTPIN (-3350 1425) $PN 2
J 2
(-3355 1435);
DISPLAY 0.617021 (-3355 1435);
PAINT ORANGE (-3355 1435);
FORCEPROP 1 LAST MATERIAL X7R
J 2
(-3400 1425);
DISPLAY 0.617021 (-3400 1425);
PAINT SKYBLUE (-3400 1425);
FORCEPROP 1 LAST TOLERANCE 10%
J 2
(-3400 1475);
DISPLAY 0.617021 (-3400 1475);
PAINT SKYBLUE (-3400 1475);
FORCEPROP 1 LAST VOLTAGE 16V
J 2
(-3400 1525);
DISPLAY 0.617021 (-3400 1525);
PAINT SKYBLUE (-3400 1525);
FORCEPROP 1 LAST LOCATION C2U18
J 2
(-3400 1625);
DISPLAY 0.617021 (-3400 1625);
PAINT AQUA (-3400 1625);
FORCEPROP 1 LAST VALUE 0.22UF
J 2
(-3400 1575);
DISPLAY 0.617021 (-3400 1575);
PAINT SKYBLUE (-3400 1575);
FORCEPROP 1 LASTPIN (-3350 1625) $PN 1
J 2
(-3355 1587);
DISPLAY 0.617021 (-3355 1587);
PAINT ORANGE (-3355 1587);
FORCEPROP 2 LAST CDS_LIB mstr_discrete
J 0
(-3350 1525);
PAINT MONO (-3350 1525);
DISPLAY INVISIBLE (-3350 1525);
FORCEPROP 1 LAST PATH I294
J 2
(-3400 1675);
DISPLAY 0.978723 (-3400 1675);
PAINT WHITE (-3400 1675);
DISPLAY INVISIBLE (-3400 1675);
FORCEPROP 2 LAST CDS_LOCATION C2U18
J 0
(-3400 1675);
DISPLAY 0.617021 (-3400 1675);
PAINT AQUA (-3400 1675);
DISPLAY INVISIBLE (-3400 1675);
FORCEPROP 2 LAST SEC_TYPE 0402
J 0
(-3400 1725);
DISPLAY 1.021277 (-3400 1725);
PAINT ORANGE (-3400 1725);
DISPLAY INVISIBLE (-3400 1725);
FORCEPROP 2 LAST SEC 1
J 0
(-3400 1750);
DISPLAY 0.680851 (-3400 1750);
PAINT MONO (-3400 1750);
DISPLAY INVISIBLE (-3400 1750);
FORCEADD OFFPAGE..1
(-3475 1125);
FORCEPROP 2 LAST $XR0 117 
J 0
(-3727 1125);
DISPLAY 0.638298 (-3727 1125);
PAINT MONO (-3727 1125);
FORCEPROP 1 LAST OFFPAGE TRUE
J 0
(-3155 995);
PAINT GREEN (-3155 995);
DISPLAY INVISIBLE (-3155 995);
FORCEPROP 2 LAST PATH I295
J 0
(-3425 1200);
DISPLAY 1.021277 (-3425 1200);
PAINT ORANGE (-3425 1200);
DISPLAY INVISIBLE (-3425 1200);
FORCEPROP 1 LAST COMMENT_BODY TRUE
J 0
(-3355 1025);
DISPLAY 2.276596 (-3355 1025);
PAINT GREEN (-3355 1025);
DISPLAY INVISIBLE (-3355 1025);
FORCEPROP 2 LAST CDS_LIB mstr_standard
J 0
(-3475 1125);
PAINT ORANGE (-3475 1125);
DISPLAY INVISIBLE (-3475 1125);
FORCEADD CAP..1
R 2
(-3100 825);
FORCEPROP 1 LAST PART_NUMBER A36096-155
R 1
J 2
(-3125 625);
DISPLAY 0.617021 (-3125 625);
PAINT BLUE (-3125 625);
FORCEPROP 1 LAST PACK_TYPE 0402
J 2
(-3150 675);
DISPLAY 0.617021 (-3150 675);
PAINT SKYBLUE (-3150 675);
FORCEPROP 1 LAST MATERIAL X7R
J 2
(-3150 725);
DISPLAY 0.617021 (-3150 725);
PAINT SKYBLUE (-3150 725);
FORCEPROP 1 LASTPIN (-3100 725) $PN 2
J 2
(-3105 735);
DISPLAY 0.617021 (-3105 735);
PAINT ORANGE (-3105 735);
FORCEPROP 1 LAST VALUE 0.22UF
J 2
(-3150 875);
DISPLAY 0.617021 (-3150 875);
PAINT SKYBLUE (-3150 875);
FORCEPROP 1 LAST VOLTAGE 16V
J 2
(-3150 825);
DISPLAY 0.617021 (-3150 825);
PAINT SKYBLUE (-3150 825);
FORCEPROP 1 LAST TOLERANCE 10%
J 2
(-3150 775);
DISPLAY 0.617021 (-3150 775);
PAINT SKYBLUE (-3150 775);
FORCEPROP 1 LAST LOCATION C2U15
J 2
(-3150 925);
DISPLAY 0.617021 (-3150 925);
PAINT AQUA (-3150 925);
FORCEPROP 1 LASTPIN (-3100 925) $PN 1
J 2
(-3105 887);
DISPLAY 0.617021 (-3105 887);
PAINT ORANGE (-3105 887);
FORCEPROP 1 LAST PATH I296
J 2
(-3150 975);
DISPLAY 0.978723 (-3150 975);
PAINT WHITE (-3150 975);
DISPLAY INVISIBLE (-3150 975);
FORCEPROP 2 LAST CDS_LIB mstr_discrete
J 0
(-3100 825);
PAINT MONO (-3100 825);
DISPLAY INVISIBLE (-3100 825);
FORCEPROP 2 LAST CDS_LOCATION C2U15
J 0
(-3150 975);
DISPLAY 0.617021 (-3150 975);
PAINT AQUA (-3150 975);
DISPLAY INVISIBLE (-3150 975);
FORCEPROP 2 LAST SEC 1
J 0
(-3150 1050);
DISPLAY 0.680851 (-3150 1050);
PAINT MONO (-3150 1050);
DISPLAY INVISIBLE (-3150 1050);
FORCEPROP 2 LAST SEC_TYPE 0402
J 0
(-3150 1025);
DISPLAY 1.021277 (-3150 1025);
PAINT ORANGE (-3150 1025);
DISPLAY INVISIBLE (-3150 1025);
FORCEADD CAP..1
R 2
(-2900 525);
FORCEPROP 1 LAST LOCATION C2U13
J 2
(-2950 625);
DISPLAY 0.617021 (-2950 625);
PAINT AQUA (-2950 625);
FORCEPROP 1 LAST VALUE 0.22UF
J 2
(-2950 575);
DISPLAY 0.617021 (-2950 575);
PAINT SKYBLUE (-2950 575);
FORCEPROP 1 LAST PACK_TYPE 0402
J 2
(-2950 375);
DISPLAY 0.617021 (-2950 375);
PAINT SKYBLUE (-2950 375);
FORCEPROP 1 LAST MATERIAL X7R
J 2
(-2950 425);
DISPLAY 0.617021 (-2950 425);
PAINT SKYBLUE (-2950 425);
FORCEPROP 1 LAST TOLERANCE 10%
J 2
(-2950 475);
DISPLAY 0.617021 (-2950 475);
PAINT SKYBLUE (-2950 475);
FORCEPROP 1 LASTPIN (-2900 425) $PN 2
J 2
(-2905 435);
DISPLAY 0.617021 (-2905 435);
PAINT ORANGE (-2905 435);
FORCEPROP 1 LAST PART_NUMBER A36096-155
R 1
J 2
(-2925 900);
DISPLAY 0.617021 (-2925 900);
PAINT BLUE (-2925 900);
FORCEPROP 1 LAST VOLTAGE 16V
J 2
(-2950 525);
DISPLAY 0.617021 (-2950 525);
PAINT SKYBLUE (-2950 525);
FORCEPROP 1 LASTPIN (-2900 625) $PN 1
J 2
(-2905 587);
DISPLAY 0.617021 (-2905 587);
PAINT ORANGE (-2905 587);
FORCEPROP 1 LAST PATH I297
J 2
(-2950 675);
DISPLAY 0.978723 (-2950 675);
PAINT WHITE (-2950 675);
DISPLAY INVISIBLE (-2950 675);
FORCEPROP 2 LAST SEC 1
J 0
(-2950 750);
DISPLAY 0.680851 (-2950 750);
PAINT MONO (-2950 750);
DISPLAY INVISIBLE (-2950 750);
FORCEPROP 2 LAST SEC_TYPE 0402
J 0
(-2950 725);
DISPLAY 1.021277 (-2950 725);
PAINT ORANGE (-2950 725);
DISPLAY INVISIBLE (-2950 725);
FORCEPROP 2 LAST CDS_LIB mstr_discrete
J 0
(-2900 525);
PAINT MONO (-2900 525);
DISPLAY INVISIBLE (-2900 525);
FORCEPROP 2 LAST CDS_LOCATION C2U13
J 0
(-2950 675);
DISPLAY 0.617021 (-2950 675);
PAINT AQUA (-2950 675);
DISPLAY INVISIBLE (-2950 675);
FORCEADD TAP..7
(-2900 275);
FORCEPROP 3 LASTPIN (-2900 325) SIG_NAME P3E_CPU0_PE1_SS_RXP<5>
J 0
(-2890 335);
DISPLAY 0.659574 (-2890 335);
PAINT MONO (-2890 335);
DISPLAY INVISIBLE (-2890 335);
FORCEPROP 1 LASTPIN (-2900 325) BN 5
R 1
J 0
(-2907 273);
DISPLAY 0.617021 (-2907 273);
PAINT GREEN (-2907 273);
FORCEPROP 2 LAST CDS_LIB mstr_standard
J 0
(-2900 275);
PAINT ORANGE (-2900 275);
DISPLAY INVISIBLE (-2900 275);
FORCEPROP 1 LAST BODY_TYPE PLUMBING
J 0
(-2850 275);
DISPLAY 2.276596 (-2850 275);
PAINT GREEN (-2850 275);
DISPLAY INVISIBLE (-2850 275);
FORCEPROP 1 LAST PATH I298
J 0
(-2902 275);
DISPLAY 0.872340 (-2902 275);
PAINT GREEN (-2902 275);
DISPLAY INVISIBLE (-2902 275);
FORCEPROP 1 LAST HDL_TAP TRUE
J 0
(-2580 145);
DISPLAY 2.276596 (-2580 145);
PAINT GREEN (-2580 145);
DISPLAY INVISIBLE (-2580 145);
FORCEADD TAP..7
(-3100 275);
FORCEPROP 3 LASTPIN (-3100 325) SIG_NAME P3E_CPU0_PE1_SS_RXP<6>
J 0
(-3090 335);
DISPLAY 0.659574 (-3090 335);
PAINT MONO (-3090 335);
DISPLAY INVISIBLE (-3090 335);
FORCEPROP 1 LASTPIN (-3100 325) BN 6
R 1
J 0
(-3107 273);
DISPLAY 0.617021 (-3107 273);
PAINT GREEN (-3107 273);
FORCEPROP 2 LAST CDS_LIB mstr_standard
J 0
(-3100 275);
PAINT ORANGE (-3100 275);
DISPLAY INVISIBLE (-3100 275);
FORCEPROP 1 LAST PATH I299
J 0
(-3102 275);
DISPLAY 0.872340 (-3102 275);
PAINT GREEN (-3102 275);
DISPLAY INVISIBLE (-3102 275);
FORCEPROP 1 LAST BODY_TYPE PLUMBING
J 0
(-3050 275);
DISPLAY 2.276596 (-3050 275);
PAINT GREEN (-3050 275);
DISPLAY INVISIBLE (-3050 275);
FORCEPROP 1 LAST HDL_TAP TRUE
J 0
(-2780 145);
DISPLAY 2.276596 (-2780 145);
PAINT GREEN (-2780 145);
DISPLAY INVISIBLE (-2780 145);
FORCEADD CAP..1
R 2
(-3300 525);
FORCEPROP 1 LAST MATERIAL X7R
J 2
(-3350 425);
DISPLAY 0.617021 (-3350 425);
PAINT SKYBLUE (-3350 425);
FORCEPROP 1 LAST PACK_TYPE 0402
J 2
(-3350 375);
DISPLAY 0.617021 (-3350 375);
PAINT SKYBLUE (-3350 375);
FORCEPROP 1 LAST TOLERANCE 10%
J 2
(-3350 475);
DISPLAY 0.617021 (-3350 475);
PAINT SKYBLUE (-3350 475);
FORCEPROP 1 LASTPIN (-3300 425) $PN 2
J 2
(-3305 435);
DISPLAY 0.617021 (-3305 435);
PAINT ORANGE (-3305 435);
FORCEPROP 1 LAST VALUE 0.22UF
J 2
(-3350 575);
DISPLAY 0.617021 (-3350 575);
PAINT SKYBLUE (-3350 575);
FORCEPROP 1 LAST LOCATION C2U17
J 2
(-3350 625);
DISPLAY 0.617021 (-3350 625);
PAINT AQUA (-3350 625);
FORCEPROP 1 LAST PART_NUMBER A36096-155
R 1
J 2
(-3350 950);
DISPLAY 0.617021 (-3350 950);
PAINT BLUE (-3350 950);
FORCEPROP 1 LAST VOLTAGE 16V
J 2
(-3350 525);
DISPLAY 0.617021 (-3350 525);
PAINT SKYBLUE (-3350 525);
FORCEPROP 1 LASTPIN (-3300 625) $PN 1
J 2
(-3305 587);
DISPLAY 0.617021 (-3305 587);
PAINT ORANGE (-3305 587);
FORCEPROP 2 LAST CDS_LOCATION C2U17
J 0
(-3350 675);
DISPLAY 0.617021 (-3350 675);
PAINT AQUA (-3350 675);
DISPLAY INVISIBLE (-3350 675);
FORCEPROP 2 LAST SEC 1
J 0
(-3350 750);
DISPLAY 0.680851 (-3350 750);
PAINT MONO (-3350 750);
DISPLAY INVISIBLE (-3350 750);
FORCEPROP 2 LAST SEC_TYPE 0402
J 0
(-3350 725);
DISPLAY 1.021277 (-3350 725);
PAINT ORANGE (-3350 725);
DISPLAY INVISIBLE (-3350 725);
FORCEPROP 1 LAST PATH I300
J 2
(-3350 675);
DISPLAY 0.978723 (-3350 675);
PAINT WHITE (-3350 675);
DISPLAY INVISIBLE (-3350 675);
FORCEPROP 2 LAST CDS_LIB mstr_discrete
J 0
(-3300 525);
PAINT MONO (-3300 525);
DISPLAY INVISIBLE (-3300 525);
FORCEADD TAP..7
(-3300 275);
FORCEPROP 3 LASTPIN (-3300 325) SIG_NAME P3E_CPU0_PE1_SS_RXP<7>
J 0
(-3290 335);
DISPLAY 0.659574 (-3290 335);
PAINT MONO (-3290 335);
DISPLAY INVISIBLE (-3290 335);
FORCEPROP 1 LASTPIN (-3300 325) BN 7
R 1
J 0
(-3307 273);
DISPLAY 0.617021 (-3307 273);
PAINT GREEN (-3307 273);
FORCEPROP 1 LAST PATH I301
J 0
(-3302 275);
DISPLAY 0.872340 (-3302 275);
PAINT GREEN (-3302 275);
DISPLAY INVISIBLE (-3302 275);
FORCEPROP 2 LAST CDS_LIB mstr_standard
J 0
(-3300 275);
PAINT ORANGE (-3300 275);
DISPLAY INVISIBLE (-3300 275);
FORCEPROP 1 LAST BODY_TYPE PLUMBING
J 0
(-3250 275);
DISPLAY 2.276596 (-3250 275);
PAINT GREEN (-3250 275);
DISPLAY INVISIBLE (-3250 275);
FORCEPROP 1 LAST HDL_TAP TRUE
J 0
(-2980 145);
DISPLAY 2.276596 (-2980 145);
PAINT GREEN (-2980 145);
DISPLAY INVISIBLE (-2980 145);
FORCEADD TAP..3
(-825 4375);
FORCEPROP 3 LASTPIN (-825 4325) SIG_NAME P3E_CPU0_PE1_SS_R_RXN<0>
J 0
(-815 4335);
DISPLAY 0.659574 (-815 4335);
PAINT MONO (-815 4335);
DISPLAY INVISIBLE (-815 4335);
FORCEPROP 1 LASTPIN (-825 4325) BN 0
R 1
J 0
(-832 4313);
DISPLAY 0.617021 (-832 4313);
PAINT GREEN (-832 4313);
FORCEPROP 1 LAST BODY_TYPE PLUMBING
J 0
(-775 4325);
DISPLAY 2.276596 (-775 4325);
PAINT GREEN (-775 4325);
DISPLAY INVISIBLE (-775 4325);
FORCEPROP 2 LAST CDS_LIB mstr_standard
J 0
(-825 4375);
PAINT MONO (-825 4375);
DISPLAY INVISIBLE (-825 4375);
FORCEPROP 1 LAST PATH I355
J 0
(-827 4375);
DISPLAY 0.872340 (-827 4375);
PAINT GREEN (-827 4375);
DISPLAY INVISIBLE (-827 4375);
FORCEPROP 1 LAST HDL_TAP TRUE
J 0
(-505 4245);
DISPLAY 2.276596 (-505 4245);
PAINT GREEN (-505 4245);
DISPLAY INVISIBLE (-505 4245);
FORCEADD TAP..3
(-1025 4375);
FORCEPROP 3 LASTPIN (-1025 4325) SIG_NAME P3E_CPU0_PE1_SS_R_RXN<1>
J 0
(-1015 4335);
DISPLAY 0.659574 (-1015 4335);
PAINT MONO (-1015 4335);
DISPLAY INVISIBLE (-1015 4335);
FORCEPROP 1 LASTPIN (-1025 4325) BN 1
R 1
J 0
(-1032 4313);
DISPLAY 0.617021 (-1032 4313);
PAINT GREEN (-1032 4313);
FORCEPROP 2 LAST CDS_LIB mstr_standard
J 0
(-1025 4375);
PAINT MONO (-1025 4375);
DISPLAY INVISIBLE (-1025 4375);
FORCEPROP 1 LAST PATH I356
J 0
(-1027 4375);
DISPLAY 0.872340 (-1027 4375);
PAINT GREEN (-1027 4375);
DISPLAY INVISIBLE (-1027 4375);
FORCEPROP 1 LAST BODY_TYPE PLUMBING
J 0
(-975 4325);
DISPLAY 2.276596 (-975 4325);
PAINT GREEN (-975 4325);
DISPLAY INVISIBLE (-975 4325);
FORCEPROP 1 LAST HDL_TAP TRUE
J 0
(-705 4245);
DISPLAY 2.276596 (-705 4245);
PAINT GREEN (-705 4245);
DISPLAY INVISIBLE (-705 4245);
FORCEADD TAP..3
(-1225 4375);
FORCEPROP 3 LASTPIN (-1225 4325) SIG_NAME P3E_CPU0_PE1_SS_R_RXN<2>
J 0
(-1215 4335);
DISPLAY 0.659574 (-1215 4335);
PAINT MONO (-1215 4335);
DISPLAY INVISIBLE (-1215 4335);
FORCEPROP 1 LASTPIN (-1225 4325) BN 2
R 1
J 0
(-1232 4313);
DISPLAY 0.617021 (-1232 4313);
PAINT GREEN (-1232 4313);
FORCEPROP 1 LAST BODY_TYPE PLUMBING
J 0
(-1175 4325);
DISPLAY 2.276596 (-1175 4325);
PAINT GREEN (-1175 4325);
DISPLAY INVISIBLE (-1175 4325);
FORCEPROP 2 LAST CDS_LIB mstr_standard
J 0
(-1225 4375);
PAINT MONO (-1225 4375);
DISPLAY INVISIBLE (-1225 4375);
FORCEPROP 1 LAST PATH I357
J 0
(-1227 4375);
DISPLAY 0.872340 (-1227 4375);
PAINT GREEN (-1227 4375);
DISPLAY INVISIBLE (-1227 4375);
FORCEPROP 1 LAST HDL_TAP TRUE
J 0
(-905 4245);
DISPLAY 2.276596 (-905 4245);
PAINT GREEN (-905 4245);
DISPLAY INVISIBLE (-905 4245);
FORCEADD TAP..3
(-1425 4375);
FORCEPROP 3 LASTPIN (-1425 4325) SIG_NAME P3E_CPU0_PE1_SS_R_RXN<3>
J 0
(-1415 4335);
DISPLAY 0.659574 (-1415 4335);
PAINT MONO (-1415 4335);
DISPLAY INVISIBLE (-1415 4335);
FORCEPROP 1 LASTPIN (-1425 4325) BN 3
R 1
J 0
(-1432 4313);
DISPLAY 0.617021 (-1432 4313);
PAINT GREEN (-1432 4313);
FORCEPROP 1 LAST BODY_TYPE PLUMBING
J 0
(-1375 4325);
DISPLAY 2.276596 (-1375 4325);
PAINT GREEN (-1375 4325);
DISPLAY INVISIBLE (-1375 4325);
FORCEPROP 2 LAST CDS_LIB mstr_standard
J 0
(-1425 4375);
PAINT MONO (-1425 4375);
DISPLAY INVISIBLE (-1425 4375);
FORCEPROP 1 LAST PATH I359
J 0
(-1427 4375);
DISPLAY 0.872340 (-1427 4375);
PAINT GREEN (-1427 4375);
DISPLAY INVISIBLE (-1427 4375);
FORCEPROP 1 LAST HDL_TAP TRUE
J 0
(-1105 4245);
DISPLAY 2.276596 (-1105 4245);
PAINT GREEN (-1105 4245);
DISPLAY INVISIBLE (-1105 4245);
FORCEADD TAP..3
(-1625 4375);
FORCEPROP 3 LASTPIN (-1625 4325) SIG_NAME P3E_CPU0_PE1_SS_R_RXN<4>
J 0
(-1615 4335);
DISPLAY 0.659574 (-1615 4335);
PAINT MONO (-1615 4335);
DISPLAY INVISIBLE (-1615 4335);
FORCEPROP 1 LASTPIN (-1625 4325) BN 4
R 1
J 0
(-1632 4313);
DISPLAY 0.617021 (-1632 4313);
PAINT GREEN (-1632 4313);
FORCEPROP 1 LAST BODY_TYPE PLUMBING
J 0
(-1575 4325);
DISPLAY 2.276596 (-1575 4325);
PAINT GREEN (-1575 4325);
DISPLAY INVISIBLE (-1575 4325);
FORCEPROP 2 LAST CDS_LIB mstr_standard
J 0
(-1625 4375);
PAINT MONO (-1625 4375);
DISPLAY INVISIBLE (-1625 4375);
FORCEPROP 1 LAST PATH I360
J 0
(-1627 4375);
DISPLAY 0.872340 (-1627 4375);
PAINT GREEN (-1627 4375);
DISPLAY INVISIBLE (-1627 4375);
FORCEPROP 1 LAST HDL_TAP TRUE
J 0
(-1305 4245);
DISPLAY 2.276596 (-1305 4245);
PAINT GREEN (-1305 4245);
DISPLAY INVISIBLE (-1305 4245);
FORCEADD TAP..3
(-1825 4375);
FORCEPROP 3 LASTPIN (-1825 4325) SIG_NAME P3E_CPU0_PE1_SS_R_RXN<5>
J 0
(-1815 4335);
DISPLAY 0.659574 (-1815 4335);
PAINT MONO (-1815 4335);
DISPLAY INVISIBLE (-1815 4335);
FORCEPROP 1 LASTPIN (-1825 4325) BN 5
R 1
J 0
(-1832 4313);
DISPLAY 0.617021 (-1832 4313);
PAINT GREEN (-1832 4313);
FORCEPROP 2 LAST CDS_LIB mstr_standard
J 0
(-1825 4375);
PAINT MONO (-1825 4375);
DISPLAY INVISIBLE (-1825 4375);
FORCEPROP 1 LAST PATH I361
J 0
(-1827 4375);
DISPLAY 0.872340 (-1827 4375);
PAINT GREEN (-1827 4375);
DISPLAY INVISIBLE (-1827 4375);
FORCEPROP 1 LAST BODY_TYPE PLUMBING
J 0
(-1775 4325);
DISPLAY 2.276596 (-1775 4325);
PAINT GREEN (-1775 4325);
DISPLAY INVISIBLE (-1775 4325);
FORCEPROP 1 LAST HDL_TAP TRUE
J 0
(-1505 4245);
DISPLAY 2.276596 (-1505 4245);
PAINT GREEN (-1505 4245);
DISPLAY INVISIBLE (-1505 4245);
FORCEADD TAP..3
(-2025 4375);
FORCEPROP 3 LASTPIN (-2025 4325) SIG_NAME P3E_CPU0_PE1_SS_R_RXN<6>
J 0
(-2015 4335);
DISPLAY 0.659574 (-2015 4335);
PAINT MONO (-2015 4335);
DISPLAY INVISIBLE (-2015 4335);
FORCEPROP 1 LASTPIN (-2025 4325) BN 6
R 1
J 0
(-2032 4313);
DISPLAY 0.617021 (-2032 4313);
PAINT GREEN (-2032 4313);
FORCEPROP 1 LAST BODY_TYPE PLUMBING
J 0
(-1975 4325);
DISPLAY 2.276596 (-1975 4325);
PAINT GREEN (-1975 4325);
DISPLAY INVISIBLE (-1975 4325);
FORCEPROP 2 LAST CDS_LIB mstr_standard
J 0
(-2025 4375);
PAINT MONO (-2025 4375);
DISPLAY INVISIBLE (-2025 4375);
FORCEPROP 1 LAST PATH I363
J 0
(-2027 4375);
DISPLAY 0.872340 (-2027 4375);
PAINT GREEN (-2027 4375);
DISPLAY INVISIBLE (-2027 4375);
FORCEPROP 1 LAST HDL_TAP TRUE
J 0
(-1705 4245);
DISPLAY 2.276596 (-1705 4245);
PAINT GREEN (-1705 4245);
DISPLAY INVISIBLE (-1705 4245);
FORCEADD TAP..3
(-2225 4375);
FORCEPROP 3 LASTPIN (-2225 4325) SIG_NAME P3E_CPU0_PE1_SS_R_RXN<7>
J 0
(-2215 4335);
DISPLAY 0.659574 (-2215 4335);
PAINT MONO (-2215 4335);
DISPLAY INVISIBLE (-2215 4335);
FORCEPROP 1 LASTPIN (-2225 4325) BN 7
R 1
J 0
(-2232 4313);
DISPLAY 0.617021 (-2232 4313);
PAINT GREEN (-2232 4313);
FORCEPROP 1 LAST BODY_TYPE PLUMBING
J 0
(-2175 4325);
DISPLAY 2.276596 (-2175 4325);
PAINT GREEN (-2175 4325);
DISPLAY INVISIBLE (-2175 4325);
FORCEPROP 2 LAST CDS_LIB mstr_standard
J 0
(-2225 4375);
PAINT MONO (-2225 4375);
DISPLAY INVISIBLE (-2225 4375);
FORCEPROP 1 LAST PATH I365
J 0
(-2227 4375);
DISPLAY 0.872340 (-2227 4375);
PAINT GREEN (-2227 4375);
DISPLAY INVISIBLE (-2227 4375);
FORCEPROP 1 LAST HDL_TAP TRUE
J 0
(-1905 4245);
DISPLAY 2.276596 (-1905 4245);
PAINT GREEN (-1905 4245);
DISPLAY INVISIBLE (-1905 4245);
FORCEADD OFFPAGE..1
(-2500 4425);
FORCEPROP 2 LAST $XR0 109 
J 0
(-2752 4425);
DISPLAY 0.638298 (-2752 4425);
PAINT MONO (-2752 4425);
FORCEPROP 2 LAST $XR1 ?
J 0
(-2872 4425);
DISPLAY 0.638298 (-2872 4425);
PAINT MONO (-2872 4425);
FORCEPROP 2 LAST PATH I366
J 0
(-2700 4475);
DISPLAY 1.021277 (-2700 4475);
PAINT ORANGE (-2700 4475);
DISPLAY INVISIBLE (-2700 4475);
FORCEPROP 1 LAST COMMENT_BODY TRUE
J 0
(-2380 4325);
DISPLAY 2.276596 (-2380 4325);
PAINT GREEN (-2380 4325);
DISPLAY INVISIBLE (-2380 4325);
FORCEPROP 2 LAST CDS_LIB mstr_standard
J 0
(-2500 4425);
PAINT MONO (-2500 4425);
DISPLAY INVISIBLE (-2500 4425);
FORCEPROP 1 LAST OFFPAGE TRUE
J 0
(-2180 4295);
PAINT GREEN (-2180 4295);
DISPLAY INVISIBLE (-2180 4295);
FORCEADD TAP..7
(-825 3575);
FORCEPROP 3 LASTPIN (-825 3625) SIG_NAME P3E_CPU0_PE1_SS_RXN<0>
J 0
(-815 3635);
DISPLAY 0.659574 (-815 3635);
PAINT MONO (-815 3635);
DISPLAY INVISIBLE (-815 3635);
FORCEPROP 1 LASTPIN (-825 3625) BN 0
R 1
J 0
(-832 3573);
DISPLAY 0.617021 (-832 3573);
PAINT GREEN (-832 3573);
FORCEPROP 2 LAST CDS_LIB mstr_standard
J 0
(-825 3575);
PAINT MONO (-825 3575);
DISPLAY INVISIBLE (-825 3575);
FORCEPROP 1 LAST BODY_TYPE PLUMBING
J 0
(-775 3575);
DISPLAY 2.276596 (-775 3575);
PAINT GREEN (-775 3575);
DISPLAY INVISIBLE (-775 3575);
FORCEPROP 1 LAST PATH I367
J 0
(-827 3575);
DISPLAY 0.872340 (-827 3575);
PAINT GREEN (-827 3575);
DISPLAY INVISIBLE (-827 3575);
FORCEPROP 1 LAST HDL_TAP TRUE
J 0
(-505 3445);
DISPLAY 2.276596 (-505 3445);
PAINT GREEN (-505 3445);
DISPLAY INVISIBLE (-505 3445);
FORCEADD OFFPAGE..2
(-675 3525);
FORCEPROP 2 LAST $XR0 107 
J 0
(-486 3525);
DISPLAY 0.638298 (-486 3525);
PAINT MONO (-486 3525);
FORCEPROP 2 LAST $XR1 30 
J 0
(-366 3525);
DISPLAY 0.638298 (-366 3525);
PAINT MONO (-366 3525);
FORCEPROP 1 LAST COMMENT_BODY TRUE
J 0
(-720 3430);
DISPLAY 0.872340 (-720 3430);
PAINT GREEN (-720 3430);
DISPLAY INVISIBLE (-720 3430);
FORCEPROP 2 LAST CDS_LIB mstr_standard
J 0
(-675 3525);
PAINT MONO (-675 3525);
DISPLAY INVISIBLE (-675 3525);
FORCEPROP 2 LAST PATH I368
J 0
(-475 3575);
DISPLAY 1.021277 (-475 3575);
PAINT ORANGE (-475 3575);
DISPLAY INVISIBLE (-475 3575);
FORCEPROP 1 LAST OFFPAGE TRUE
J 0
(-350 3400);
DISPLAY 0.872340 (-350 3400);
PAINT GREEN (-350 3400);
DISPLAY INVISIBLE (-350 3400);
FORCEADD OFFPAGE..2
(-600 2500);
FORCEPROP 2 LAST $XR0 107 
J 0
(-411 2500);
DISPLAY 0.638298 (-411 2500);
PAINT MONO (-411 2500);
FORCEPROP 2 LAST $XR1 30 
J 0
(-291 2500);
DISPLAY 0.638298 (-291 2500);
PAINT MONO (-291 2500);
FORCEPROP 1 LAST COMMENT_BODY TRUE
J 0
(-645 2405);
DISPLAY 0.872340 (-645 2405);
PAINT GREEN (-645 2405);
DISPLAY INVISIBLE (-645 2405);
FORCEPROP 2 LAST CDS_LIB mstr_standard
J 0
(-600 2500);
PAINT MONO (-600 2500);
DISPLAY INVISIBLE (-600 2500);
FORCEPROP 2 LAST PATH I369
J 0
(-400 2550);
DISPLAY 1.021277 (-400 2550);
PAINT ORANGE (-400 2550);
DISPLAY INVISIBLE (-400 2550);
FORCEPROP 1 LAST OFFPAGE TRUE
J 0
(-275 2375);
DISPLAY 0.872340 (-275 2375);
PAINT GREEN (-275 2375);
DISPLAY INVISIBLE (-275 2375);
FORCEADD TAP..7
(-1025 3575);
FORCEPROP 3 LASTPIN (-1025 3625) SIG_NAME P3E_CPU0_PE1_SS_RXN<1>
J 0
(-1015 3635);
DISPLAY 0.659574 (-1015 3635);
PAINT MONO (-1015 3635);
DISPLAY INVISIBLE (-1015 3635);
FORCEPROP 1 LASTPIN (-1025 3625) BN 1
R 1
J 0
(-1032 3573);
DISPLAY 0.617021 (-1032 3573);
PAINT GREEN (-1032 3573);
FORCEPROP 2 LAST CDS_LIB mstr_standard
J 0
(-1025 3575);
PAINT MONO (-1025 3575);
DISPLAY INVISIBLE (-1025 3575);
FORCEPROP 1 LAST PATH I371
J 0
(-1027 3575);
DISPLAY 0.872340 (-1027 3575);
PAINT GREEN (-1027 3575);
DISPLAY INVISIBLE (-1027 3575);
FORCEPROP 1 LAST HDL_TAP TRUE
J 0
(-705 3445);
DISPLAY 2.276596 (-705 3445);
PAINT GREEN (-705 3445);
DISPLAY INVISIBLE (-705 3445);
FORCEPROP 1 LAST BODY_TYPE PLUMBING
J 0
(-975 3575);
DISPLAY 2.276596 (-975 3575);
PAINT GREEN (-975 3575);
DISPLAY INVISIBLE (-975 3575);
FORCEADD TAP..7
(-1225 3575);
FORCEPROP 3 LASTPIN (-1225 3625) SIG_NAME P3E_CPU0_PE1_SS_RXN<2>
J 0
(-1215 3635);
DISPLAY 0.659574 (-1215 3635);
PAINT MONO (-1215 3635);
DISPLAY INVISIBLE (-1215 3635);
FORCEPROP 1 LASTPIN (-1225 3625) BN 2
R 1
J 0
(-1232 3573);
DISPLAY 0.617021 (-1232 3573);
PAINT GREEN (-1232 3573);
FORCEPROP 2 LAST CDS_LIB mstr_standard
J 0
(-1225 3575);
PAINT MONO (-1225 3575);
DISPLAY INVISIBLE (-1225 3575);
FORCEPROP 1 LAST BODY_TYPE PLUMBING
J 0
(-1175 3575);
DISPLAY 2.276596 (-1175 3575);
PAINT GREEN (-1175 3575);
DISPLAY INVISIBLE (-1175 3575);
FORCEPROP 1 LAST PATH I372
J 0
(-1227 3575);
DISPLAY 0.872340 (-1227 3575);
PAINT GREEN (-1227 3575);
DISPLAY INVISIBLE (-1227 3575);
FORCEPROP 1 LAST HDL_TAP TRUE
J 0
(-905 3445);
DISPLAY 2.276596 (-905 3445);
PAINT GREEN (-905 3445);
DISPLAY INVISIBLE (-905 3445);
FORCEADD TAP..3
(-800 3350);
FORCEPROP 3 LASTPIN (-800 3300) SIG_NAME P3E_CPU0_PE1_SS_R_RXP<0>
J 0
(-790 3310);
DISPLAY 0.659574 (-790 3310);
PAINT MONO (-790 3310);
DISPLAY INVISIBLE (-790 3310);
FORCEPROP 1 LASTPIN (-800 3300) BN 0
R 1
J 0
(-807 3288);
DISPLAY 0.617021 (-807 3288);
PAINT GREEN (-807 3288);
FORCEPROP 1 LAST PATH I373
J 0
(-802 3350);
DISPLAY 0.872340 (-802 3350);
PAINT GREEN (-802 3350);
DISPLAY INVISIBLE (-802 3350);
FORCEPROP 2 LAST CDS_LIB mstr_standard
J 0
(-800 3350);
PAINT MONO (-800 3350);
DISPLAY INVISIBLE (-800 3350);
FORCEPROP 1 LAST BODY_TYPE PLUMBING
J 0
(-750 3300);
DISPLAY 2.276596 (-750 3300);
PAINT GREEN (-750 3300);
DISPLAY INVISIBLE (-750 3300);
FORCEPROP 1 LAST HDL_TAP TRUE
J 0
(-480 3220);
DISPLAY 2.276596 (-480 3220);
PAINT GREEN (-480 3220);
DISPLAY INVISIBLE (-480 3220);
FORCEADD TAP..3
(-1000 3350);
FORCEPROP 3 LASTPIN (-1000 3300) SIG_NAME P3E_CPU0_PE1_SS_R_RXP<1>
J 0
(-990 3310);
DISPLAY 0.659574 (-990 3310);
PAINT MONO (-990 3310);
DISPLAY INVISIBLE (-990 3310);
FORCEPROP 1 LASTPIN (-1000 3300) BN 1
R 1
J 0
(-1007 3288);
DISPLAY 0.617021 (-1007 3288);
PAINT GREEN (-1007 3288);
FORCEPROP 1 LAST BODY_TYPE PLUMBING
J 0
(-950 3300);
DISPLAY 2.276596 (-950 3300);
PAINT GREEN (-950 3300);
DISPLAY INVISIBLE (-950 3300);
FORCEPROP 1 LAST PATH I375
J 0
(-1002 3350);
DISPLAY 0.872340 (-1002 3350);
PAINT GREEN (-1002 3350);
DISPLAY INVISIBLE (-1002 3350);
FORCEPROP 2 LAST CDS_LIB mstr_standard
J 0
(-1000 3350);
PAINT MONO (-1000 3350);
DISPLAY INVISIBLE (-1000 3350);
FORCEPROP 1 LAST HDL_TAP TRUE
J 0
(-680 3220);
DISPLAY 2.276596 (-680 3220);
PAINT GREEN (-680 3220);
DISPLAY INVISIBLE (-680 3220);
FORCEADD TAP..3
(-1200 3350);
FORCEPROP 3 LASTPIN (-1200 3300) SIG_NAME P3E_CPU0_PE1_SS_R_RXP<2>
J 0
(-1190 3310);
DISPLAY 0.659574 (-1190 3310);
PAINT MONO (-1190 3310);
DISPLAY INVISIBLE (-1190 3310);
FORCEPROP 1 LASTPIN (-1200 3300) BN 2
R 1
J 0
(-1207 3288);
DISPLAY 0.617021 (-1207 3288);
PAINT GREEN (-1207 3288);
FORCEPROP 1 LAST BODY_TYPE PLUMBING
J 0
(-1150 3300);
DISPLAY 2.276596 (-1150 3300);
PAINT GREEN (-1150 3300);
DISPLAY INVISIBLE (-1150 3300);
FORCEPROP 1 LAST PATH I376
J 0
(-1202 3350);
DISPLAY 0.872340 (-1202 3350);
PAINT GREEN (-1202 3350);
DISPLAY INVISIBLE (-1202 3350);
FORCEPROP 2 LAST CDS_LIB mstr_standard
J 0
(-1200 3350);
PAINT MONO (-1200 3350);
DISPLAY INVISIBLE (-1200 3350);
FORCEPROP 1 LAST HDL_TAP TRUE
J 0
(-880 3220);
DISPLAY 1.829787 (-880 3220);
PAINT GREEN (-880 3220);
DISPLAY INVISIBLE (-880 3220);
FORCEADD TAP..7
(-1425 3575);
FORCEPROP 3 LASTPIN (-1425 3625) SIG_NAME P3E_CPU0_PE1_SS_RXN<3>
J 0
(-1415 3635);
DISPLAY 0.659574 (-1415 3635);
PAINT MONO (-1415 3635);
DISPLAY INVISIBLE (-1415 3635);
FORCEPROP 1 LASTPIN (-1425 3625) BN 3
R 1
J 0
(-1432 3573);
DISPLAY 0.617021 (-1432 3573);
PAINT GREEN (-1432 3573);
FORCEPROP 1 LAST HDL_TAP TRUE
J 0
(-1105 3445);
DISPLAY 2.276596 (-1105 3445);
PAINT GREEN (-1105 3445);
DISPLAY INVISIBLE (-1105 3445);
FORCEPROP 2 LAST CDS_LIB mstr_standard
J 0
(-1425 3575);
PAINT MONO (-1425 3575);
DISPLAY INVISIBLE (-1425 3575);
FORCEPROP 1 LAST BODY_TYPE PLUMBING
J 0
(-1375 3575);
DISPLAY 2.276596 (-1375 3575);
PAINT GREEN (-1375 3575);
DISPLAY INVISIBLE (-1375 3575);
FORCEPROP 1 LAST PATH I379
J 0
(-1427 3575);
DISPLAY 0.872340 (-1427 3575);
PAINT GREEN (-1427 3575);
DISPLAY INVISIBLE (-1427 3575);
FORCEADD TAP..7
(-1625 3575);
FORCEPROP 3 LASTPIN (-1625 3625) SIG_NAME P3E_CPU0_PE1_SS_RXN<4>
J 0
(-1615 3635);
DISPLAY 0.659574 (-1615 3635);
PAINT MONO (-1615 3635);
DISPLAY INVISIBLE (-1615 3635);
FORCEPROP 1 LASTPIN (-1625 3625) BN 4
R 1
J 0
(-1632 3573);
DISPLAY 0.617021 (-1632 3573);
PAINT GREEN (-1632 3573);
FORCEPROP 2 LAST CDS_LIB mstr_standard
J 0
(-1625 3575);
PAINT MONO (-1625 3575);
DISPLAY INVISIBLE (-1625 3575);
FORCEPROP 1 LAST BODY_TYPE PLUMBING
J 0
(-1575 3575);
DISPLAY 2.276596 (-1575 3575);
PAINT GREEN (-1575 3575);
DISPLAY INVISIBLE (-1575 3575);
FORCEPROP 1 LAST PATH I380
J 0
(-1627 3575);
DISPLAY 0.872340 (-1627 3575);
PAINT GREEN (-1627 3575);
DISPLAY INVISIBLE (-1627 3575);
FORCEPROP 1 LAST HDL_TAP TRUE
J 0
(-1305 3445);
DISPLAY 2.276596 (-1305 3445);
PAINT GREEN (-1305 3445);
DISPLAY INVISIBLE (-1305 3445);
FORCEADD TAP..7
(-1825 3575);
FORCEPROP 3 LASTPIN (-1825 3625) SIG_NAME P3E_CPU0_PE1_SS_RXN<5>
J 0
(-1815 3635);
DISPLAY 0.659574 (-1815 3635);
PAINT MONO (-1815 3635);
DISPLAY INVISIBLE (-1815 3635);
FORCEPROP 1 LASTPIN (-1825 3625) BN 5
R 1
J 0
(-1832 3573);
DISPLAY 0.617021 (-1832 3573);
PAINT GREEN (-1832 3573);
FORCEPROP 2 LAST CDS_LIB mstr_standard
J 0
(-1825 3575);
PAINT MONO (-1825 3575);
DISPLAY INVISIBLE (-1825 3575);
FORCEPROP 1 LAST BODY_TYPE PLUMBING
J 0
(-1775 3575);
DISPLAY 2.276596 (-1775 3575);
PAINT GREEN (-1775 3575);
DISPLAY INVISIBLE (-1775 3575);
FORCEPROP 1 LAST PATH I382
J 0
(-1827 3575);
DISPLAY 0.872340 (-1827 3575);
PAINT GREEN (-1827 3575);
DISPLAY INVISIBLE (-1827 3575);
FORCEPROP 1 LAST HDL_TAP TRUE
J 0
(-1505 3445);
DISPLAY 2.276596 (-1505 3445);
PAINT GREEN (-1505 3445);
DISPLAY INVISIBLE (-1505 3445);
FORCEADD TAP..3
(-1400 3350);
FORCEPROP 3 LASTPIN (-1400 3300) SIG_NAME P3E_CPU0_PE1_SS_R_RXP<3>
J 0
(-1390 3310);
DISPLAY 0.659574 (-1390 3310);
PAINT MONO (-1390 3310);
DISPLAY INVISIBLE (-1390 3310);
FORCEPROP 1 LASTPIN (-1400 3300) BN 3
R 1
J 0
(-1407 3288);
DISPLAY 0.617021 (-1407 3288);
PAINT GREEN (-1407 3288);
FORCEPROP 1 LAST BODY_TYPE PLUMBING
J 0
(-1350 3300);
DISPLAY 2.276596 (-1350 3300);
PAINT GREEN (-1350 3300);
DISPLAY INVISIBLE (-1350 3300);
FORCEPROP 2 LAST CDS_LIB mstr_standard
J 0
(-1400 3350);
PAINT MONO (-1400 3350);
DISPLAY INVISIBLE (-1400 3350);
FORCEPROP 1 LAST PATH I383
J 0
(-1402 3350);
DISPLAY 0.872340 (-1402 3350);
PAINT GREEN (-1402 3350);
DISPLAY INVISIBLE (-1402 3350);
FORCEPROP 1 LAST HDL_TAP TRUE
J 0
(-1080 3220);
DISPLAY 2.276596 (-1080 3220);
PAINT GREEN (-1080 3220);
DISPLAY INVISIBLE (-1080 3220);
FORCEADD TAP..3
(-1600 3350);
FORCEPROP 3 LASTPIN (-1600 3300) SIG_NAME P3E_CPU0_PE1_SS_R_RXP<4>
J 0
(-1590 3310);
DISPLAY 0.659574 (-1590 3310);
PAINT MONO (-1590 3310);
DISPLAY INVISIBLE (-1590 3310);
FORCEPROP 1 LASTPIN (-1600 3300) BN 4
R 1
J 0
(-1607 3288);
DISPLAY 0.617021 (-1607 3288);
PAINT GREEN (-1607 3288);
FORCEPROP 1 LAST BODY_TYPE PLUMBING
J 0
(-1550 3300);
DISPLAY 2.276596 (-1550 3300);
PAINT GREEN (-1550 3300);
DISPLAY INVISIBLE (-1550 3300);
FORCEPROP 2 LAST CDS_LIB mstr_standard
J 0
(-1600 3350);
PAINT MONO (-1600 3350);
DISPLAY INVISIBLE (-1600 3350);
FORCEPROP 1 LAST PATH I384
J 0
(-1602 3350);
DISPLAY 0.872340 (-1602 3350);
PAINT GREEN (-1602 3350);
DISPLAY INVISIBLE (-1602 3350);
FORCEPROP 1 LAST HDL_TAP TRUE
J 0
(-1280 3220);
DISPLAY 2.276596 (-1280 3220);
PAINT GREEN (-1280 3220);
DISPLAY INVISIBLE (-1280 3220);
FORCEADD TAP..7
(-800 2550);
FORCEPROP 3 LASTPIN (-800 2600) SIG_NAME P3E_CPU0_PE1_SS_RXP<0>
J 0
(-790 2610);
DISPLAY 0.659574 (-790 2610);
PAINT MONO (-790 2610);
DISPLAY INVISIBLE (-790 2610);
FORCEPROP 1 LASTPIN (-800 2600) BN 0
R 1
J 0
(-807 2548);
DISPLAY 0.617021 (-807 2548);
PAINT GREEN (-807 2548);
FORCEPROP 2 LAST CDS_LIB mstr_standard
J 0
(-800 2550);
PAINT MONO (-800 2550);
DISPLAY INVISIBLE (-800 2550);
FORCEPROP 1 LAST BODY_TYPE PLUMBING
J 0
(-750 2550);
DISPLAY 2.276596 (-750 2550);
PAINT GREEN (-750 2550);
DISPLAY INVISIBLE (-750 2550);
FORCEPROP 1 LAST PATH I386
J 0
(-802 2550);
DISPLAY 0.872340 (-802 2550);
PAINT GREEN (-802 2550);
DISPLAY INVISIBLE (-802 2550);
FORCEPROP 1 LAST HDL_TAP TRUE
J 0
(-480 2420);
DISPLAY 2.276596 (-480 2420);
PAINT GREEN (-480 2420);
DISPLAY INVISIBLE (-480 2420);
FORCEADD TAP..7
(-1000 2550);
FORCEPROP 3 LASTPIN (-1000 2600) SIG_NAME P3E_CPU0_PE1_SS_RXP<1>
J 0
(-990 2610);
DISPLAY 0.659574 (-990 2610);
PAINT MONO (-990 2610);
DISPLAY INVISIBLE (-990 2610);
FORCEPROP 1 LASTPIN (-1000 2600) BN 1
R 1
J 0
(-1007 2548);
DISPLAY 0.617021 (-1007 2548);
PAINT GREEN (-1007 2548);
FORCEPROP 1 LAST HDL_TAP TRUE
J 0
(-680 2420);
DISPLAY 2.276596 (-680 2420);
PAINT GREEN (-680 2420);
DISPLAY INVISIBLE (-680 2420);
FORCEPROP 2 LAST CDS_LIB mstr_standard
J 0
(-1000 2550);
PAINT MONO (-1000 2550);
DISPLAY INVISIBLE (-1000 2550);
FORCEPROP 1 LAST BODY_TYPE PLUMBING
J 0
(-950 2550);
DISPLAY 2.276596 (-950 2550);
PAINT GREEN (-950 2550);
DISPLAY INVISIBLE (-950 2550);
FORCEPROP 1 LAST PATH I388
J 0
(-1002 2550);
DISPLAY 0.872340 (-1002 2550);
PAINT GREEN (-1002 2550);
DISPLAY INVISIBLE (-1002 2550);
FORCEADD TAP..7
(-1200 2550);
FORCEPROP 3 LASTPIN (-1200 2600) SIG_NAME P3E_CPU0_PE1_SS_RXP<2>
J 0
(-1190 2610);
DISPLAY 0.659574 (-1190 2610);
PAINT MONO (-1190 2610);
DISPLAY INVISIBLE (-1190 2610);
FORCEPROP 1 LASTPIN (-1200 2600) BN 2
R 1
J 0
(-1207 2548);
DISPLAY 0.617021 (-1207 2548);
PAINT GREEN (-1207 2548);
FORCEPROP 2 LAST CDS_LIB mstr_standard
J 0
(-1200 2550);
PAINT MONO (-1200 2550);
DISPLAY INVISIBLE (-1200 2550);
FORCEPROP 1 LAST BODY_TYPE PLUMBING
J 0
(-1150 2550);
DISPLAY 2.276596 (-1150 2550);
PAINT GREEN (-1150 2550);
DISPLAY INVISIBLE (-1150 2550);
FORCEPROP 1 LAST PATH I389
J 0
(-1202 2550);
DISPLAY 0.872340 (-1202 2550);
PAINT GREEN (-1202 2550);
DISPLAY INVISIBLE (-1202 2550);
FORCEPROP 1 LAST HDL_TAP TRUE
J 0
(-880 2420);
DISPLAY 2.276596 (-880 2420);
PAINT GREEN (-880 2420);
DISPLAY INVISIBLE (-880 2420);
FORCEADD TAP..7
(-1400 2550);
FORCEPROP 3 LASTPIN (-1400 2600) SIG_NAME P3E_CPU0_PE1_SS_RXP<3>
J 0
(-1390 2610);
DISPLAY 0.659574 (-1390 2610);
PAINT MONO (-1390 2610);
DISPLAY INVISIBLE (-1390 2610);
FORCEPROP 1 LASTPIN (-1400 2600) BN 3
R 1
J 0
(-1407 2548);
DISPLAY 0.617021 (-1407 2548);
PAINT GREEN (-1407 2548);
FORCEPROP 1 LAST HDL_TAP TRUE
J 0
(-1080 2420);
DISPLAY 2.276596 (-1080 2420);
PAINT GREEN (-1080 2420);
DISPLAY INVISIBLE (-1080 2420);
FORCEPROP 2 LAST CDS_LIB mstr_standard
J 0
(-1400 2550);
PAINT MONO (-1400 2550);
DISPLAY INVISIBLE (-1400 2550);
FORCEPROP 1 LAST BODY_TYPE PLUMBING
J 0
(-1350 2550);
DISPLAY 2.276596 (-1350 2550);
PAINT GREEN (-1350 2550);
DISPLAY INVISIBLE (-1350 2550);
FORCEPROP 1 LAST PATH I391
J 0
(-1402 2550);
DISPLAY 0.872340 (-1402 2550);
PAINT GREEN (-1402 2550);
DISPLAY INVISIBLE (-1402 2550);
FORCEADD TAP..7
(-1600 2550);
FORCEPROP 3 LASTPIN (-1600 2600) SIG_NAME P3E_CPU0_PE1_SS_RXP<4>
J 0
(-1590 2610);
DISPLAY 0.659574 (-1590 2610);
PAINT MONO (-1590 2610);
DISPLAY INVISIBLE (-1590 2610);
FORCEPROP 1 LASTPIN (-1600 2600) BN 4
R 1
J 0
(-1607 2548);
DISPLAY 0.617021 (-1607 2548);
PAINT GREEN (-1607 2548);
FORCEPROP 2 LAST CDS_LIB mstr_standard
J 0
(-1600 2550);
PAINT MONO (-1600 2550);
DISPLAY INVISIBLE (-1600 2550);
FORCEPROP 1 LAST BODY_TYPE PLUMBING
J 0
(-1550 2550);
DISPLAY 2.276596 (-1550 2550);
PAINT GREEN (-1550 2550);
DISPLAY INVISIBLE (-1550 2550);
FORCEPROP 1 LAST PATH I392
J 0
(-1602 2550);
DISPLAY 0.872340 (-1602 2550);
PAINT GREEN (-1602 2550);
DISPLAY INVISIBLE (-1602 2550);
FORCEPROP 1 LAST HDL_TAP TRUE
J 0
(-1280 2420);
DISPLAY 2.276596 (-1280 2420);
PAINT GREEN (-1280 2420);
DISPLAY INVISIBLE (-1280 2420);
FORCEADD TAP..7
(-2025 3575);
FORCEPROP 3 LASTPIN (-2025 3625) SIG_NAME P3E_CPU0_PE1_SS_RXN<6>
J 0
(-2015 3635);
DISPLAY 0.659574 (-2015 3635);
PAINT MONO (-2015 3635);
DISPLAY INVISIBLE (-2015 3635);
FORCEPROP 1 LASTPIN (-2025 3625) BN 6
R 1
J 0
(-2032 3573);
DISPLAY 0.617021 (-2032 3573);
PAINT GREEN (-2032 3573);
FORCEPROP 1 LAST HDL_TAP TRUE
J 0
(-1705 3445);
DISPLAY 2.276596 (-1705 3445);
PAINT GREEN (-1705 3445);
DISPLAY INVISIBLE (-1705 3445);
FORCEPROP 2 LAST CDS_LIB mstr_standard
J 0
(-2025 3575);
PAINT MONO (-2025 3575);
DISPLAY INVISIBLE (-2025 3575);
FORCEPROP 1 LAST BODY_TYPE PLUMBING
J 0
(-1975 3575);
DISPLAY 2.276596 (-1975 3575);
PAINT GREEN (-1975 3575);
DISPLAY INVISIBLE (-1975 3575);
FORCEPROP 1 LAST PATH I393
J 0
(-2027 3575);
DISPLAY 0.872340 (-2027 3575);
PAINT GREEN (-2027 3575);
DISPLAY INVISIBLE (-2027 3575);
FORCEADD TAP..7
(-2225 3575);
FORCEPROP 3 LASTPIN (-2225 3625) SIG_NAME P3E_CPU0_PE1_SS_RXN<7>
J 0
(-2215 3635);
DISPLAY 0.659574 (-2215 3635);
PAINT MONO (-2215 3635);
DISPLAY INVISIBLE (-2215 3635);
FORCEPROP 1 LASTPIN (-2225 3625) BN 7
R 1
J 0
(-2232 3573);
DISPLAY 0.617021 (-2232 3573);
PAINT GREEN (-2232 3573);
FORCEPROP 2 LAST CDS_LIB mstr_standard
J 0
(-2225 3575);
PAINT MONO (-2225 3575);
DISPLAY INVISIBLE (-2225 3575);
FORCEPROP 1 LAST BODY_TYPE PLUMBING
J 0
(-2175 3575);
DISPLAY 2.276596 (-2175 3575);
PAINT GREEN (-2175 3575);
DISPLAY INVISIBLE (-2175 3575);
FORCEPROP 1 LAST PATH I395
J 0
(-2227 3575);
DISPLAY 0.872340 (-2227 3575);
PAINT GREEN (-2227 3575);
DISPLAY INVISIBLE (-2227 3575);
FORCEPROP 1 LAST HDL_TAP TRUE
J 0
(-1905 3445);
DISPLAY 2.276596 (-1905 3445);
PAINT GREEN (-1905 3445);
DISPLAY INVISIBLE (-1905 3445);
FORCEADD TAP..3
(-1800 3350);
FORCEPROP 3 LASTPIN (-1800 3300) SIG_NAME P3E_CPU0_PE1_SS_R_RXP<5>
J 0
(-1790 3310);
DISPLAY 0.659574 (-1790 3310);
PAINT MONO (-1790 3310);
DISPLAY INVISIBLE (-1790 3310);
FORCEPROP 1 LASTPIN (-1800 3300) BN 5
R 1
J 0
(-1807 3288);
DISPLAY 0.617021 (-1807 3288);
PAINT GREEN (-1807 3288);
FORCEPROP 2 LAST CDS_LIB mstr_standard
J 0
(-1800 3350);
PAINT MONO (-1800 3350);
DISPLAY INVISIBLE (-1800 3350);
FORCEPROP 1 LAST PATH I396
J 0
(-1802 3350);
DISPLAY 0.872340 (-1802 3350);
PAINT GREEN (-1802 3350);
DISPLAY INVISIBLE (-1802 3350);
FORCEPROP 1 LAST BODY_TYPE PLUMBING
J 0
(-1750 3300);
DISPLAY 2.276596 (-1750 3300);
PAINT GREEN (-1750 3300);
DISPLAY INVISIBLE (-1750 3300);
FORCEPROP 1 LAST HDL_TAP TRUE
J 0
(-1480 3220);
DISPLAY 2.276596 (-1480 3220);
PAINT GREEN (-1480 3220);
DISPLAY INVISIBLE (-1480 3220);
FORCEADD TAP..3
(-2000 3350);
FORCEPROP 3 LASTPIN (-2000 3300) SIG_NAME P3E_CPU0_PE1_SS_R_RXP<6>
J 0
(-1990 3310);
DISPLAY 0.659574 (-1990 3310);
PAINT MONO (-1990 3310);
DISPLAY INVISIBLE (-1990 3310);
FORCEPROP 1 LASTPIN (-2000 3300) BN 6
R 1
J 0
(-2007 3288);
DISPLAY 0.617021 (-2007 3288);
PAINT GREEN (-2007 3288);
FORCEPROP 1 LAST BODY_TYPE PLUMBING
J 0
(-1950 3300);
DISPLAY 2.276596 (-1950 3300);
PAINT GREEN (-1950 3300);
DISPLAY INVISIBLE (-1950 3300);
FORCEPROP 1 LAST PATH I397
J 0
(-2002 3350);
DISPLAY 0.872340 (-2002 3350);
PAINT GREEN (-2002 3350);
DISPLAY INVISIBLE (-2002 3350);
FORCEPROP 2 LAST CDS_LIB mstr_standard
J 0
(-2000 3350);
PAINT MONO (-2000 3350);
DISPLAY INVISIBLE (-2000 3350);
FORCEPROP 1 LAST HDL_TAP TRUE
J 0
(-1680 3220);
DISPLAY 2.276596 (-1680 3220);
PAINT GREEN (-1680 3220);
DISPLAY INVISIBLE (-1680 3220);
FORCEADD TAP..3
(-2200 3350);
FORCEPROP 3 LASTPIN (-2200 3300) SIG_NAME P3E_CPU0_PE1_SS_R_RXP<7>
J 0
(-2190 3310);
DISPLAY 0.659574 (-2190 3310);
PAINT MONO (-2190 3310);
DISPLAY INVISIBLE (-2190 3310);
FORCEPROP 1 LASTPIN (-2200 3300) BN 7
R 1
J 0
(-2207 3288);
DISPLAY 0.617021 (-2207 3288);
PAINT GREEN (-2207 3288);
FORCEPROP 1 LAST BODY_TYPE PLUMBING
J 0
(-2150 3300);
DISPLAY 2.276596 (-2150 3300);
PAINT GREEN (-2150 3300);
DISPLAY INVISIBLE (-2150 3300);
FORCEPROP 2 LAST CDS_LIB mstr_standard
J 0
(-2200 3350);
PAINT MONO (-2200 3350);
DISPLAY INVISIBLE (-2200 3350);
FORCEPROP 1 LAST PATH I399
J 0
(-2202 3350);
DISPLAY 0.872340 (-2202 3350);
PAINT GREEN (-2202 3350);
DISPLAY INVISIBLE (-2202 3350);
FORCEPROP 1 LAST HDL_TAP TRUE
J 0
(-1880 3220);
DISPLAY 2.276596 (-1880 3220);
PAINT GREEN (-1880 3220);
DISPLAY INVISIBLE (-1880 3220);
FORCEADD OFFPAGE..1
(-2375 3400);
FORCEPROP 2 LAST $XR0 109 
J 0
(-2627 3400);
DISPLAY 0.638298 (-2627 3400);
PAINT MONO (-2627 3400);
FORCEPROP 2 LAST PATH I400
J 0
(-2575 3450);
DISPLAY 1.021277 (-2575 3450);
PAINT ORANGE (-2575 3450);
DISPLAY INVISIBLE (-2575 3450);
FORCEPROP 2 LAST CDS_LIB mstr_standard
J 0
(-2375 3400);
PAINT MONO (-2375 3400);
DISPLAY INVISIBLE (-2375 3400);
FORCEPROP 1 LAST OFFPAGE TRUE
J 0
(-2055 3270);
PAINT GREEN (-2055 3270);
DISPLAY INVISIBLE (-2055 3270);
FORCEPROP 1 LAST COMMENT_BODY TRUE
J 0
(-2255 3300);
DISPLAY 2.276596 (-2255 3300);
PAINT GREEN (-2255 3300);
DISPLAY INVISIBLE (-2255 3300);
FORCEADD TAP..7
(-1800 2550);
FORCEPROP 3 LASTPIN (-1800 2600) SIG_NAME P3E_CPU0_PE1_SS_RXP<5>
J 0
(-1790 2610);
DISPLAY 0.659574 (-1790 2610);
PAINT MONO (-1790 2610);
DISPLAY INVISIBLE (-1790 2610);
FORCEPROP 1 LASTPIN (-1800 2600) BN 5
R 1
J 0
(-1807 2548);
DISPLAY 0.617021 (-1807 2548);
PAINT GREEN (-1807 2548);
FORCEPROP 2 LAST CDS_LIB mstr_standard
J 0
(-1800 2550);
PAINT MONO (-1800 2550);
DISPLAY INVISIBLE (-1800 2550);
FORCEPROP 1 LAST BODY_TYPE PLUMBING
J 0
(-1750 2550);
DISPLAY 2.276596 (-1750 2550);
PAINT GREEN (-1750 2550);
DISPLAY INVISIBLE (-1750 2550);
FORCEPROP 1 LAST PATH I402
J 0
(-1802 2550);
DISPLAY 0.872340 (-1802 2550);
PAINT GREEN (-1802 2550);
DISPLAY INVISIBLE (-1802 2550);
FORCEPROP 1 LAST HDL_TAP TRUE
J 0
(-1480 2420);
DISPLAY 2.276596 (-1480 2420);
PAINT GREEN (-1480 2420);
DISPLAY INVISIBLE (-1480 2420);
FORCEADD TAP..7
(-2000 2550);
FORCEPROP 3 LASTPIN (-2000 2600) SIG_NAME P3E_CPU0_PE1_SS_RXP<6>
J 0
(-1990 2610);
DISPLAY 0.659574 (-1990 2610);
PAINT MONO (-1990 2610);
DISPLAY INVISIBLE (-1990 2610);
FORCEPROP 1 LASTPIN (-2000 2600) BN 6
R 1
J 0
(-2007 2548);
DISPLAY 0.617021 (-2007 2548);
PAINT GREEN (-2007 2548);
FORCEPROP 1 LAST HDL_TAP TRUE
J 0
(-1680 2420);
DISPLAY 2.276596 (-1680 2420);
PAINT GREEN (-1680 2420);
DISPLAY INVISIBLE (-1680 2420);
FORCEPROP 2 LAST CDS_LIB mstr_standard
J 0
(-2000 2550);
PAINT MONO (-2000 2550);
DISPLAY INVISIBLE (-2000 2550);
FORCEPROP 1 LAST BODY_TYPE PLUMBING
J 0
(-1950 2550);
DISPLAY 2.276596 (-1950 2550);
PAINT GREEN (-1950 2550);
DISPLAY INVISIBLE (-1950 2550);
FORCEPROP 1 LAST PATH I403
J 0
(-2002 2550);
DISPLAY 0.872340 (-2002 2550);
PAINT GREEN (-2002 2550);
DISPLAY INVISIBLE (-2002 2550);
FORCEADD TAP..7
(-2200 2550);
FORCEPROP 3 LASTPIN (-2200 2600) SIG_NAME P3E_CPU0_PE1_SS_RXP<7>
J 0
(-2190 2610);
DISPLAY 0.659574 (-2190 2610);
PAINT MONO (-2190 2610);
DISPLAY INVISIBLE (-2190 2610);
FORCEPROP 1 LASTPIN (-2200 2600) BN 7
R 1
J 0
(-2207 2548);
DISPLAY 0.617021 (-2207 2548);
PAINT GREEN (-2207 2548);
FORCEPROP 2 LAST CDS_LIB mstr_standard
J 0
(-2200 2550);
PAINT MONO (-2200 2550);
DISPLAY INVISIBLE (-2200 2550);
FORCEPROP 1 LAST BODY_TYPE PLUMBING
J 0
(-2150 2550);
DISPLAY 2.276596 (-2150 2550);
PAINT GREEN (-2150 2550);
DISPLAY INVISIBLE (-2150 2550);
FORCEPROP 1 LAST PATH I405
J 0
(-2202 2550);
DISPLAY 0.872340 (-2202 2550);
PAINT GREEN (-2202 2550);
DISPLAY INVISIBLE (-2202 2550);
FORCEPROP 1 LAST HDL_TAP TRUE
J 0
(-1880 2420);
DISPLAY 2.276596 (-1880 2420);
PAINT GREEN (-1880 2420);
DISPLAY INVISIBLE (-1880 2420);
FORCEADD TAP..7
(-5450 2425);
FORCEPROP 3 LASTPIN (-5450 2475) SIG_NAME P3E_CPU0_PE1_SS_C_TXP<6>
J 0
(-5440 2485);
DISPLAY 0.659574 (-5440 2485);
PAINT MONO (-5440 2485);
DISPLAY INVISIBLE (-5440 2485);
FORCEPROP 1 LASTPIN (-5450 2475) BN 6
R 1
J 0
(-5457 2423);
DISPLAY 0.617021 (-5457 2423);
PAINT GREEN (-5457 2423);
FORCEPROP 1 LAST BODY_TYPE PLUMBING
J 0
(-5400 2425);
DISPLAY 2.276596 (-5400 2425);
PAINT GREEN (-5400 2425);
DISPLAY INVISIBLE (-5400 2425);
FORCEPROP 1 LAST PATH I406
J 0
(-5452 2425);
DISPLAY 0.872340 (-5452 2425);
PAINT GREEN (-5452 2425);
DISPLAY INVISIBLE (-5452 2425);
FORCEPROP 2 LAST CDS_LIB mstr_standard
J 0
(-5450 2425);
PAINT ORANGE (-5450 2425);
DISPLAY INVISIBLE (-5450 2425);
FORCEPROP 1 LAST HDL_TAP TRUE
J 0
(-5130 2295);
DISPLAY 2.276596 (-5130 2295);
PAINT GREEN (-5130 2295);
DISPLAY INVISIBLE (-5130 2295);
FORCEADD TAP..3
(-4300 4225);
FORCEPROP 3 LASTPIN (-4300 4175) SIG_NAME P3E_CPU0_PE1_SS_TXN<0>
J 0
(-4290 4185);
DISPLAY 0.659574 (-4290 4185);
PAINT MONO (-4290 4185);
DISPLAY INVISIBLE (-4290 4185);
FORCEPROP 1 LASTPIN (-4300 4175) BN 0
R 1
J 0
(-4307 4163);
DISPLAY 0.617021 (-4307 4163);
PAINT GREEN (-4307 4163);
FORCEPROP 2 LAST CDS_LIB mstr_standard
J 0
(-4300 4225);
PAINT ORANGE (-4300 4225);
DISPLAY INVISIBLE (-4300 4225);
FORCEPROP 1 LAST BODY_TYPE PLUMBING
J 0
(-4250 4175);
DISPLAY 2.276596 (-4250 4175);
PAINT GREEN (-4250 4175);
DISPLAY INVISIBLE (-4250 4175);
FORCEPROP 1 LAST PATH I407
J 0
(-4302 4225);
DISPLAY 0.872340 (-4302 4225);
PAINT GREEN (-4302 4225);
DISPLAY INVISIBLE (-4302 4225);
FORCEPROP 1 LAST HDL_TAP TRUE
J 0
(-3980 4095);
DISPLAY 2.276596 (-3980 4095);
PAINT GREEN (-3980 4095);
DISPLAY INVISIBLE (-3980 4095);
FORCEADD TAP..3
(-4500 4225);
FORCEPROP 3 LASTPIN (-4500 4175) SIG_NAME P3E_CPU0_PE1_SS_TXN<1>
J 0
(-4490 4185);
DISPLAY 0.659574 (-4490 4185);
PAINT MONO (-4490 4185);
DISPLAY INVISIBLE (-4490 4185);
FORCEPROP 1 LASTPIN (-4500 4175) BN 1
R 1
J 0
(-4507 4163);
DISPLAY 0.617021 (-4507 4163);
PAINT GREEN (-4507 4163);
FORCEPROP 1 LAST HDL_TAP TRUE
J 0
(-4180 4095);
DISPLAY 2.276596 (-4180 4095);
PAINT GREEN (-4180 4095);
DISPLAY INVISIBLE (-4180 4095);
FORCEPROP 2 LAST CDS_LIB mstr_standard
J 0
(-4500 4225);
PAINT ORANGE (-4500 4225);
DISPLAY INVISIBLE (-4500 4225);
FORCEPROP 1 LAST BODY_TYPE PLUMBING
J 0
(-4450 4175);
DISPLAY 2.276596 (-4450 4175);
PAINT GREEN (-4450 4175);
DISPLAY INVISIBLE (-4450 4175);
FORCEPROP 1 LAST PATH I408
J 0
(-4502 4225);
DISPLAY 0.872340 (-4502 4225);
PAINT GREEN (-4502 4225);
DISPLAY INVISIBLE (-4502 4225);
FORCEADD TAP..3
(-4700 4225);
FORCEPROP 3 LASTPIN (-4700 4175) SIG_NAME P3E_CPU0_PE1_SS_TXN<2>
J 0
(-4690 4185);
DISPLAY 0.659574 (-4690 4185);
PAINT MONO (-4690 4185);
DISPLAY INVISIBLE (-4690 4185);
FORCEPROP 1 LASTPIN (-4700 4175) BN 2
R 1
J 0
(-4707 4163);
DISPLAY 0.617021 (-4707 4163);
PAINT GREEN (-4707 4163);
FORCEPROP 1 LAST HDL_TAP TRUE
J 0
(-4380 4095);
DISPLAY 2.276596 (-4380 4095);
PAINT GREEN (-4380 4095);
DISPLAY INVISIBLE (-4380 4095);
FORCEPROP 2 LAST CDS_LIB mstr_standard
J 0
(-4700 4225);
PAINT ORANGE (-4700 4225);
DISPLAY INVISIBLE (-4700 4225);
FORCEPROP 1 LAST BODY_TYPE PLUMBING
J 0
(-4650 4175);
DISPLAY 2.276596 (-4650 4175);
PAINT GREEN (-4650 4175);
DISPLAY INVISIBLE (-4650 4175);
FORCEPROP 1 LAST PATH I409
J 0
(-4702 4225);
DISPLAY 0.872340 (-4702 4225);
PAINT GREEN (-4702 4225);
DISPLAY INVISIBLE (-4702 4225);
FORCEADD TAP..3
(-4900 4225);
FORCEPROP 3 LASTPIN (-4900 4175) SIG_NAME P3E_CPU0_PE1_SS_TXN<3>
J 0
(-4890 4185);
DISPLAY 0.659574 (-4890 4185);
PAINT MONO (-4890 4185);
DISPLAY INVISIBLE (-4890 4185);
FORCEPROP 1 LASTPIN (-4900 4175) BN 3
R 1
J 0
(-4907 4163);
DISPLAY 0.617021 (-4907 4163);
PAINT GREEN (-4907 4163);
FORCEPROP 1 LAST HDL_TAP TRUE
J 0
(-4580 4095);
DISPLAY 2.276596 (-4580 4095);
PAINT GREEN (-4580 4095);
DISPLAY INVISIBLE (-4580 4095);
FORCEPROP 2 LAST CDS_LIB mstr_standard
J 0
(-4900 4225);
PAINT ORANGE (-4900 4225);
DISPLAY INVISIBLE (-4900 4225);
FORCEPROP 1 LAST PATH I410
J 0
(-4902 4225);
DISPLAY 0.872340 (-4902 4225);
PAINT GREEN (-4902 4225);
DISPLAY INVISIBLE (-4902 4225);
FORCEPROP 1 LAST BODY_TYPE PLUMBING
J 0
(-4850 4175);
DISPLAY 2.276596 (-4850 4175);
PAINT GREEN (-4850 4175);
DISPLAY INVISIBLE (-4850 4175);
FORCEADD TAP..3
(-5100 4225);
FORCEPROP 3 LASTPIN (-5100 4175) SIG_NAME P3E_CPU0_PE1_SS_TXN<4>
J 0
(-5090 4185);
DISPLAY 0.659574 (-5090 4185);
PAINT MONO (-5090 4185);
DISPLAY INVISIBLE (-5090 4185);
FORCEPROP 1 LASTPIN (-5100 4175) BN 4
R 1
J 0
(-5107 4163);
DISPLAY 0.617021 (-5107 4163);
PAINT GREEN (-5107 4163);
FORCEPROP 1 LAST HDL_TAP TRUE
J 0
(-4780 4095);
DISPLAY 2.276596 (-4780 4095);
PAINT GREEN (-4780 4095);
DISPLAY INVISIBLE (-4780 4095);
FORCEPROP 2 LAST CDS_LIB mstr_standard
J 0
(-5100 4225);
PAINT ORANGE (-5100 4225);
DISPLAY INVISIBLE (-5100 4225);
FORCEPROP 1 LAST BODY_TYPE PLUMBING
J 0
(-5050 4175);
DISPLAY 2.276596 (-5050 4175);
PAINT GREEN (-5050 4175);
DISPLAY INVISIBLE (-5050 4175);
FORCEPROP 1 LAST PATH I411
J 0
(-5102 4225);
DISPLAY 0.872340 (-5102 4225);
PAINT GREEN (-5102 4225);
DISPLAY INVISIBLE (-5102 4225);
FORCEADD TAP..3
(-5300 4225);
FORCEPROP 3 LASTPIN (-5300 4175) SIG_NAME P3E_CPU0_PE1_SS_TXN<5>
J 0
(-5290 4185);
DISPLAY 0.659574 (-5290 4185);
PAINT MONO (-5290 4185);
DISPLAY INVISIBLE (-5290 4185);
FORCEPROP 1 LASTPIN (-5300 4175) BN 5
R 1
J 0
(-5307 4163);
DISPLAY 0.617021 (-5307 4163);
PAINT GREEN (-5307 4163);
FORCEPROP 1 LAST HDL_TAP TRUE
J 0
(-4980 4095);
DISPLAY 2.276596 (-4980 4095);
PAINT GREEN (-4980 4095);
DISPLAY INVISIBLE (-4980 4095);
FORCEPROP 2 LAST CDS_LIB mstr_standard
J 0
(-5300 4225);
PAINT ORANGE (-5300 4225);
DISPLAY INVISIBLE (-5300 4225);
FORCEPROP 1 LAST BODY_TYPE PLUMBING
J 0
(-5250 4175);
DISPLAY 2.276596 (-5250 4175);
PAINT GREEN (-5250 4175);
DISPLAY INVISIBLE (-5250 4175);
FORCEPROP 1 LAST PATH I412
J 0
(-5302 4225);
DISPLAY 0.872340 (-5302 4225);
PAINT GREEN (-5302 4225);
DISPLAY INVISIBLE (-5302 4225);
FORCEADD TAP..3
(-5500 4225);
FORCEPROP 3 LASTPIN (-5500 4175) SIG_NAME P3E_CPU0_PE1_SS_TXN<6>
J 0
(-5490 4185);
DISPLAY 0.659574 (-5490 4185);
PAINT MONO (-5490 4185);
DISPLAY INVISIBLE (-5490 4185);
FORCEPROP 1 LASTPIN (-5500 4175) BN 6
R 1
J 0
(-5507 4163);
DISPLAY 0.617021 (-5507 4163);
PAINT GREEN (-5507 4163);
FORCEPROP 1 LAST HDL_TAP TRUE
J 0
(-5180 4095);
DISPLAY 2.276596 (-5180 4095);
PAINT GREEN (-5180 4095);
DISPLAY INVISIBLE (-5180 4095);
FORCEPROP 2 LAST CDS_LIB mstr_standard
J 0
(-5500 4225);
PAINT ORANGE (-5500 4225);
DISPLAY INVISIBLE (-5500 4225);
FORCEPROP 1 LAST BODY_TYPE PLUMBING
J 0
(-5450 4175);
DISPLAY 2.276596 (-5450 4175);
PAINT GREEN (-5450 4175);
DISPLAY INVISIBLE (-5450 4175);
FORCEPROP 1 LAST PATH I413
J 0
(-5502 4225);
DISPLAY 0.872340 (-5502 4225);
PAINT GREEN (-5502 4225);
DISPLAY INVISIBLE (-5502 4225);
FORCEADD TAP..3
(-5700 4225);
FORCEPROP 3 LASTPIN (-5700 4175) SIG_NAME P3E_CPU0_PE1_SS_TXN<7>
J 0
(-5690 4185);
DISPLAY 0.659574 (-5690 4185);
PAINT MONO (-5690 4185);
DISPLAY INVISIBLE (-5690 4185);
FORCEPROP 1 LASTPIN (-5700 4175) BN 7
R 1
J 0
(-5707 4163);
DISPLAY 0.617021 (-5707 4163);
PAINT GREEN (-5707 4163);
FORCEPROP 1 LAST HDL_TAP TRUE
J 0
(-5380 4095);
DISPLAY 2.276596 (-5380 4095);
PAINT GREEN (-5380 4095);
DISPLAY INVISIBLE (-5380 4095);
FORCEPROP 2 LAST CDS_LIB mstr_standard
J 0
(-5700 4225);
PAINT ORANGE (-5700 4225);
DISPLAY INVISIBLE (-5700 4225);
FORCEPROP 1 LAST BODY_TYPE PLUMBING
J 0
(-5650 4175);
DISPLAY 2.276596 (-5650 4175);
PAINT GREEN (-5650 4175);
DISPLAY INVISIBLE (-5650 4175);
FORCEPROP 1 LAST PATH I414
J 0
(-5702 4225);
DISPLAY 0.872340 (-5702 4225);
PAINT GREEN (-5702 4225);
DISPLAY INVISIBLE (-5702 4225);
FORCEADD CAP..1
R 2
(-4300 3975);
FORCEPROP 1 LAST PART_NUMBER A36096-155
J 2
(-4350 3825);
DISPLAY 0.617021 (-4350 3825);
PAINT BLUE (-4350 3825);
FORCEPROP 1 LAST MATERIAL EMPTY
J 2
(-4350 3875);
DISPLAY 0.617021 (-4350 3875);
PAINT RED (-4350 3875);
FORCEPROP 1 LAST VALUE 0.22UF
J 2
(-4350 4025);
DISPLAY 0.617021 (-4350 4025);
PAINT SKYBLUE (-4350 4025);
FORCEPROP 1 LAST TOLERANCE 10%
J 2
(-4350 3925);
DISPLAY 0.617021 (-4350 3925);
PAINT SKYBLUE (-4350 3925);
FORCEPROP 1 LAST PACK_TYPE 0402
J 2
(-4350 3775);
DISPLAY 0.617021 (-4350 3775);
PAINT SKYBLUE (-4350 3775);
FORCEPROP 1 LAST VOLTAGE 16V
J 2
(-4350 3975);
DISPLAY 0.617021 (-4350 3975);
PAINT SKYBLUE (-4350 3975);
FORCEPROP 1 LAST LOCATION C3P12
J 2
(-4350 4075);
DISPLAY 0.617021 (-4350 4075);
PAINT AQUA (-4350 4075);
FORCEPROP 1 LASTPIN (-4300 3875) $PN 2
J 2
(-4310 3855);
DISPLAY 0.787234 (-4310 3855);
PAINT ORANGE (-4310 3855);
DISPLAY INVISIBLE (-4310 3855);
FORCEPROP 1 LASTPIN (-4300 4075) $PN 1
J 2
(-4310 4055);
DISPLAY 0.787234 (-4310 4055);
PAINT ORANGE (-4310 4055);
DISPLAY INVISIBLE (-4310 4055);
FORCEPROP 2 LAST CDS_LIB mstr_discrete
J 0
(-4300 3975);
PAINT ORANGE (-4300 3975);
DISPLAY INVISIBLE (-4300 3975);
FORCEPROP 2 LAST CDS_LOCATION C3P12
J 2
(-4350 4075);
DISPLAY 0.617021 (-4350 4075);
PAINT AQUA (-4350 4075);
DISPLAY INVISIBLE (-4350 4075);
FORCEPROP 2 LAST CDS_SEC 1
J 0
(-4350 4175);
DISPLAY 1.021277 (-4350 4175);
PAINT ORANGE (-4350 4175);
DISPLAY INVISIBLE (-4350 4175);
FORCEPROP 2 LAST $SEC 1
J 0
(-4350 4175);
DISPLAY 0.680851 (-4350 4175);
PAINT MONO (-4350 4175);
DISPLAY INVISIBLE (-4350 4175);
FORCEPROP 1 LAST PATH I415
J 2
(-4350 4125);
DISPLAY 0.978723 (-4350 4125);
PAINT WHITE (-4350 4125);
DISPLAY INVISIBLE (-4350 4125);
FORCEADD OFFPAGE..2
(-4050 3375);
FORCEPROP 2 LAST $XR0 109 
J 0
(-3861 3375);
DISPLAY 0.638298 (-3861 3375);
PAINT MONO (-3861 3375);
FORCEPROP 1 LAST COMMENT_BODY TRUE
J 0
(-4095 3280);
DISPLAY 0.872340 (-4095 3280);
PAINT GREEN (-4095 3280);
DISPLAY INVISIBLE (-4095 3280);
FORCEPROP 2 LAST CDS_LIB mstr_standard
J 0
(-4050 3375);
PAINT ORANGE (-4050 3375);
DISPLAY INVISIBLE (-4050 3375);
FORCEPROP 2 LAST PATH I416
J 0
(-3875 3450);
DISPLAY 1.021277 (-3875 3450);
PAINT ORANGE (-3875 3450);
DISPLAY INVISIBLE (-3875 3450);
FORCEPROP 1 LAST OFFPAGE TRUE
J 0
(-3725 3250);
DISPLAY 0.872340 (-3725 3250);
PAINT GREEN (-3725 3250);
DISPLAY INVISIBLE (-3725 3250);
FORCEADD CAP..1
R 2
(-4250 2975);
FORCEPROP 1 LAST MATERIAL EMPTY
J 2
(-4300 2875);
DISPLAY 0.617021 (-4300 2875);
PAINT RED (-4300 2875);
FORCEPROP 1 LAST PART_NUMBER A36096-155
J 2
(-4300 2825);
DISPLAY 0.617021 (-4300 2825);
PAINT BLUE (-4300 2825);
FORCEPROP 1 LAST VALUE 0.22UF
J 2
(-4300 3025);
DISPLAY 0.617021 (-4300 3025);
PAINT SKYBLUE (-4300 3025);
FORCEPROP 1 LAST TOLERANCE 10%
J 2
(-4300 2925);
DISPLAY 0.617021 (-4300 2925);
PAINT SKYBLUE (-4300 2925);
FORCEPROP 1 LAST PACK_TYPE 0402
J 2
(-4300 2775);
DISPLAY 0.617021 (-4300 2775);
PAINT SKYBLUE (-4300 2775);
FORCEPROP 1 LAST VOLTAGE 16V
J 2
(-4300 2975);
DISPLAY 0.617021 (-4300 2975);
PAINT SKYBLUE (-4300 2975);
FORCEPROP 1 LAST LOCATION C3P10
J 2
(-4300 3075);
DISPLAY 0.617021 (-4300 3075);
PAINT AQUA (-4300 3075);
FORCEPROP 1 LASTPIN (-4250 2875) $PN 2
J 2
(-4260 2855);
DISPLAY 0.787234 (-4260 2855);
PAINT ORANGE (-4260 2855);
DISPLAY INVISIBLE (-4260 2855);
FORCEPROP 2 LAST CDS_LIB mstr_discrete
J 0
(-4250 2975);
PAINT ORANGE (-4250 2975);
DISPLAY INVISIBLE (-4250 2975);
FORCEPROP 1 LASTPIN (-4250 3075) $PN 1
J 2
(-4260 3055);
DISPLAY 0.787234 (-4260 3055);
PAINT ORANGE (-4260 3055);
DISPLAY INVISIBLE (-4260 3055);
FORCEPROP 1 LAST PATH I417
J 2
(-4300 3125);
DISPLAY 0.978723 (-4300 3125);
PAINT WHITE (-4300 3125);
DISPLAY INVISIBLE (-4300 3125);
FORCEPROP 2 LAST CDS_LOCATION C3P10
J 2
(-4300 3075);
DISPLAY 0.617021 (-4300 3075);
PAINT AQUA (-4300 3075);
DISPLAY INVISIBLE (-4300 3075);
FORCEPROP 2 LAST CDS_SEC 1
J 0
(-4300 3175);
DISPLAY 1.021277 (-4300 3175);
PAINT ORANGE (-4300 3175);
DISPLAY INVISIBLE (-4300 3175);
FORCEPROP 2 LAST $SEC 1
J 0
(-4300 3175);
DISPLAY 0.680851 (-4300 3175);
PAINT MONO (-4300 3175);
DISPLAY INVISIBLE (-4300 3175);
FORCEADD TAP..7
(-4300 3425);
FORCEPROP 3 LASTPIN (-4300 3475) SIG_NAME P3E_CPU0_PE1_SS_C_TXN<0>
J 0
(-4290 3485);
DISPLAY 0.659574 (-4290 3485);
PAINT MONO (-4290 3485);
DISPLAY INVISIBLE (-4290 3485);
FORCEPROP 1 LASTPIN (-4300 3475) BN 0
R 1
J 0
(-4307 3423);
DISPLAY 0.617021 (-4307 3423);
PAINT GREEN (-4307 3423);
FORCEPROP 2 LAST CDS_LIB mstr_standard
J 0
(-4300 3425);
PAINT ORANGE (-4300 3425);
DISPLAY INVISIBLE (-4300 3425);
FORCEPROP 1 LAST BODY_TYPE PLUMBING
J 0
(-4250 3425);
DISPLAY 2.276596 (-4250 3425);
PAINT GREEN (-4250 3425);
DISPLAY INVISIBLE (-4250 3425);
FORCEPROP 1 LAST PATH I418
J 0
(-4302 3425);
DISPLAY 0.872340 (-4302 3425);
PAINT GREEN (-4302 3425);
DISPLAY INVISIBLE (-4302 3425);
FORCEPROP 1 LAST HDL_TAP TRUE
J 0
(-3980 3295);
DISPLAY 2.276596 (-3980 3295);
PAINT GREEN (-3980 3295);
DISPLAY INVISIBLE (-3980 3295);
FORCEADD TAP..3
(-4250 3225);
FORCEPROP 3 LASTPIN (-4250 3175) SIG_NAME P3E_CPU0_PE1_SS_TXP<0>
J 0
(-4240 3185);
DISPLAY 0.659574 (-4240 3185);
PAINT MONO (-4240 3185);
DISPLAY INVISIBLE (-4240 3185);
FORCEPROP 1 LASTPIN (-4250 3175) BN 0
R 1
J 0
(-4257 3163);
DISPLAY 0.617021 (-4257 3163);
PAINT GREEN (-4257 3163);
FORCEPROP 2 LAST CDS_LIB mstr_standard
J 0
(-4250 3225);
PAINT ORANGE (-4250 3225);
DISPLAY INVISIBLE (-4250 3225);
FORCEPROP 1 LAST PATH I419
J 0
(-4252 3225);
DISPLAY 0.872340 (-4252 3225);
PAINT GREEN (-4252 3225);
DISPLAY INVISIBLE (-4252 3225);
FORCEPROP 1 LAST BODY_TYPE PLUMBING
J 0
(-4200 3175);
DISPLAY 2.276596 (-4200 3175);
PAINT GREEN (-4200 3175);
DISPLAY INVISIBLE (-4200 3175);
FORCEPROP 1 LAST HDL_TAP TRUE
J 0
(-3930 3095);
DISPLAY 2.276596 (-3930 3095);
PAINT GREEN (-3930 3095);
DISPLAY INVISIBLE (-3930 3095);
FORCEADD TAP..3
(-4450 3225);
FORCEPROP 3 LASTPIN (-4450 3175) SIG_NAME P3E_CPU0_PE1_SS_TXP<1>
J 0
(-4440 3185);
DISPLAY 0.659574 (-4440 3185);
PAINT MONO (-4440 3185);
DISPLAY INVISIBLE (-4440 3185);
FORCEPROP 1 LASTPIN (-4450 3175) BN 1
R 1
J 0
(-4457 3163);
DISPLAY 0.617021 (-4457 3163);
PAINT GREEN (-4457 3163);
FORCEPROP 2 LAST CDS_LIB mstr_standard
J 0
(-4450 3225);
PAINT ORANGE (-4450 3225);
DISPLAY INVISIBLE (-4450 3225);
FORCEPROP 1 LAST BODY_TYPE PLUMBING
J 0
(-4400 3175);
DISPLAY 2.276596 (-4400 3175);
PAINT GREEN (-4400 3175);
DISPLAY INVISIBLE (-4400 3175);
FORCEPROP 1 LAST PATH I420
J 0
(-4452 3225);
DISPLAY 0.872340 (-4452 3225);
PAINT GREEN (-4452 3225);
DISPLAY INVISIBLE (-4452 3225);
FORCEPROP 1 LAST HDL_TAP TRUE
J 0
(-4130 3095);
DISPLAY 2.276596 (-4130 3095);
PAINT GREEN (-4130 3095);
DISPLAY INVISIBLE (-4130 3095);
FORCEADD TAP..7
(-4500 3425);
FORCEPROP 3 LASTPIN (-4500 3475) SIG_NAME P3E_CPU0_PE1_SS_C_TXN<1>
J 0
(-4490 3485);
DISPLAY 0.659574 (-4490 3485);
PAINT MONO (-4490 3485);
DISPLAY INVISIBLE (-4490 3485);
FORCEPROP 1 LASTPIN (-4500 3475) BN 1
R 1
J 0
(-4507 3423);
DISPLAY 0.617021 (-4507 3423);
PAINT GREEN (-4507 3423);
FORCEPROP 2 LAST CDS_LIB mstr_standard
J 0
(-4500 3425);
PAINT ORANGE (-4500 3425);
DISPLAY INVISIBLE (-4500 3425);
FORCEPROP 1 LAST BODY_TYPE PLUMBING
J 0
(-4450 3425);
DISPLAY 2.276596 (-4450 3425);
PAINT GREEN (-4450 3425);
DISPLAY INVISIBLE (-4450 3425);
FORCEPROP 1 LAST PATH I421
J 0
(-4502 3425);
DISPLAY 0.872340 (-4502 3425);
PAINT GREEN (-4502 3425);
DISPLAY INVISIBLE (-4502 3425);
FORCEPROP 1 LAST HDL_TAP TRUE
J 0
(-4180 3295);
DISPLAY 2.276596 (-4180 3295);
PAINT GREEN (-4180 3295);
DISPLAY INVISIBLE (-4180 3295);
FORCEADD CAP..1
R 2
(-4500 3700);
FORCEPROP 1 LAST MATERIAL EMPTY
J 2
(-4550 3600);
DISPLAY 0.617021 (-4550 3600);
PAINT RED (-4550 3600);
FORCEPROP 1 LAST LOCATION C3P16
J 2
(-4550 3800);
DISPLAY 0.617021 (-4550 3800);
PAINT AQUA (-4550 3800);
FORCEPROP 1 LAST PART_NUMBER A36096-155
J 2
(-4550 3550);
DISPLAY 0.617021 (-4550 3550);
PAINT BLUE (-4550 3550);
FORCEPROP 1 LAST VALUE 0.22UF
J 2
(-4550 3750);
DISPLAY 0.617021 (-4550 3750);
PAINT SKYBLUE (-4550 3750);
FORCEPROP 1 LAST TOLERANCE 10%
J 2
(-4550 3650);
DISPLAY 0.617021 (-4550 3650);
PAINT SKYBLUE (-4550 3650);
FORCEPROP 1 LAST PACK_TYPE 0402
J 2
(-4550 3500);
DISPLAY 0.617021 (-4550 3500);
PAINT SKYBLUE (-4550 3500);
FORCEPROP 1 LAST VOLTAGE 16V
J 2
(-4550 3700);
DISPLAY 0.617021 (-4550 3700);
PAINT SKYBLUE (-4550 3700);
FORCEPROP 1 LASTPIN (-4500 3600) $PN 2
J 2
(-4510 3580);
DISPLAY 0.787234 (-4510 3580);
PAINT ORANGE (-4510 3580);
DISPLAY INVISIBLE (-4510 3580);
FORCEPROP 2 LAST CDS_LIB mstr_discrete
J 0
(-4500 3700);
PAINT ORANGE (-4500 3700);
DISPLAY INVISIBLE (-4500 3700);
FORCEPROP 2 LAST CDS_LOCATION C3P16
J 2
(-4550 3800);
DISPLAY 0.617021 (-4550 3800);
PAINT AQUA (-4550 3800);
DISPLAY INVISIBLE (-4550 3800);
FORCEPROP 1 LASTPIN (-4500 3800) $PN 1
J 2
(-4510 3780);
DISPLAY 0.787234 (-4510 3780);
PAINT ORANGE (-4510 3780);
DISPLAY INVISIBLE (-4510 3780);
FORCEPROP 2 LAST CDS_SEC 1
J 0
(-4550 3900);
DISPLAY 1.021277 (-4550 3900);
PAINT ORANGE (-4550 3900);
DISPLAY INVISIBLE (-4550 3900);
FORCEPROP 2 LAST $SEC 1
J 0
(-4550 3900);
DISPLAY 0.680851 (-4550 3900);
PAINT MONO (-4550 3900);
DISPLAY INVISIBLE (-4550 3900);
FORCEPROP 1 LAST PATH I422
J 2
(-4550 3850);
DISPLAY 0.978723 (-4550 3850);
PAINT WHITE (-4550 3850);
DISPLAY INVISIBLE (-4550 3850);
FORCEADD CAP..1
R 2
(-4700 3975);
FORCEPROP 1 LAST MATERIAL EMPTY
J 2
(-4750 3875);
DISPLAY 0.617021 (-4750 3875);
PAINT RED (-4750 3875);
FORCEPROP 1 LAST PART_NUMBER A36096-155
J 2
(-4750 3825);
DISPLAY 0.617021 (-4750 3825);
PAINT BLUE (-4750 3825);
FORCEPROP 1 LAST VALUE 0.22UF
J 2
(-4750 4025);
DISPLAY 0.617021 (-4750 4025);
PAINT SKYBLUE (-4750 4025);
FORCEPROP 1 LAST PACK_TYPE 0402
J 2
(-4750 3775);
DISPLAY 0.617021 (-4750 3775);
PAINT SKYBLUE (-4750 3775);
FORCEPROP 1 LAST TOLERANCE 10%
J 2
(-4750 3925);
DISPLAY 0.617021 (-4750 3925);
PAINT SKYBLUE (-4750 3925);
FORCEPROP 1 LAST VOLTAGE 16V
J 2
(-4750 3975);
DISPLAY 0.617021 (-4750 3975);
PAINT SKYBLUE (-4750 3975);
FORCEPROP 1 LAST LOCATION C3P21
J 2
(-4750 4075);
DISPLAY 0.617021 (-4750 4075);
PAINT AQUA (-4750 4075);
FORCEPROP 1 LASTPIN (-4700 3875) $PN 2
J 2
(-4710 3855);
DISPLAY 0.787234 (-4710 3855);
PAINT ORANGE (-4710 3855);
DISPLAY INVISIBLE (-4710 3855);
FORCEPROP 1 LASTPIN (-4700 4075) $PN 1
J 2
(-4710 4055);
DISPLAY 0.787234 (-4710 4055);
PAINT ORANGE (-4710 4055);
DISPLAY INVISIBLE (-4710 4055);
FORCEPROP 2 LAST CDS_LIB mstr_discrete
J 0
(-4700 3975);
PAINT ORANGE (-4700 3975);
DISPLAY INVISIBLE (-4700 3975);
FORCEPROP 2 LAST CDS_LOCATION C3P21
J 2
(-4750 4075);
DISPLAY 0.617021 (-4750 4075);
PAINT AQUA (-4750 4075);
DISPLAY INVISIBLE (-4750 4075);
FORCEPROP 1 LAST PATH I423
J 2
(-4750 4125);
DISPLAY 0.978723 (-4750 4125);
PAINT WHITE (-4750 4125);
DISPLAY INVISIBLE (-4750 4125);
FORCEPROP 2 LAST CDS_SEC 1
J 0
(-4750 4175);
DISPLAY 1.021277 (-4750 4175);
PAINT ORANGE (-4750 4175);
DISPLAY INVISIBLE (-4750 4175);
FORCEPROP 2 LAST $SEC 1
J 0
(-4750 4175);
DISPLAY 0.680851 (-4750 4175);
PAINT MONO (-4750 4175);
DISPLAY INVISIBLE (-4750 4175);
FORCEADD CAP..1
R 2
(-4900 3675);
FORCEPROP 1 LAST PART_NUMBER A36096-155
J 2
(-4950 3525);
DISPLAY 0.617021 (-4950 3525);
PAINT BLUE (-4950 3525);
FORCEPROP 1 LAST VALUE 0.22UF
J 2
(-4950 3725);
DISPLAY 0.617021 (-4950 3725);
PAINT SKYBLUE (-4950 3725);
FORCEPROP 1 LAST PACK_TYPE 0402
J 2
(-4950 3475);
DISPLAY 0.617021 (-4950 3475);
PAINT SKYBLUE (-4950 3475);
FORCEPROP 1 LAST MATERIAL EMPTY
J 2
(-4950 3575);
DISPLAY 0.617021 (-4950 3575);
PAINT RED (-4950 3575);
FORCEPROP 1 LAST LOCATION C3P24
J 2
(-4950 3775);
DISPLAY 0.617021 (-4950 3775);
PAINT AQUA (-4950 3775);
FORCEPROP 1 LAST TOLERANCE 10%
J 2
(-4950 3625);
DISPLAY 0.617021 (-4950 3625);
PAINT SKYBLUE (-4950 3625);
FORCEPROP 1 LAST VOLTAGE 16V
J 2
(-4950 3675);
DISPLAY 0.617021 (-4950 3675);
PAINT SKYBLUE (-4950 3675);
FORCEPROP 1 LASTPIN (-4900 3575) $PN 2
J 2
(-4910 3555);
DISPLAY 0.787234 (-4910 3555);
PAINT ORANGE (-4910 3555);
DISPLAY INVISIBLE (-4910 3555);
FORCEPROP 2 LAST CDS_LIB mstr_discrete
J 0
(-4900 3675);
PAINT ORANGE (-4900 3675);
DISPLAY INVISIBLE (-4900 3675);
FORCEPROP 1 LASTPIN (-4900 3775) $PN 1
J 2
(-4910 3755);
DISPLAY 0.787234 (-4910 3755);
PAINT ORANGE (-4910 3755);
DISPLAY INVISIBLE (-4910 3755);
FORCEPROP 2 LAST CDS_LOCATION C3P24
J 2
(-4950 3775);
DISPLAY 0.617021 (-4950 3775);
PAINT AQUA (-4950 3775);
DISPLAY INVISIBLE (-4950 3775);
FORCEPROP 1 LAST PATH I424
J 2
(-4950 3825);
DISPLAY 0.978723 (-4950 3825);
PAINT WHITE (-4950 3825);
DISPLAY INVISIBLE (-4950 3825);
FORCEPROP 2 LAST CDS_SEC 1
J 0
(-4950 3875);
DISPLAY 1.021277 (-4950 3875);
PAINT ORANGE (-4950 3875);
DISPLAY INVISIBLE (-4950 3875);
FORCEPROP 2 LAST $SEC 1
J 0
(-4950 3875);
DISPLAY 0.680851 (-4950 3875);
PAINT MONO (-4950 3875);
DISPLAY INVISIBLE (-4950 3875);
FORCEADD TAP..3
(-4650 3225);
FORCEPROP 3 LASTPIN (-4650 3175) SIG_NAME P3E_CPU0_PE1_SS_TXP<2>
J 0
(-4640 3185);
DISPLAY 0.659574 (-4640 3185);
PAINT MONO (-4640 3185);
DISPLAY INVISIBLE (-4640 3185);
FORCEPROP 1 LASTPIN (-4650 3175) BN 2
R 1
J 0
(-4657 3163);
DISPLAY 0.617021 (-4657 3163);
PAINT GREEN (-4657 3163);
FORCEPROP 1 LAST PATH I425
J 0
(-4652 3225);
DISPLAY 0.872340 (-4652 3225);
PAINT GREEN (-4652 3225);
DISPLAY INVISIBLE (-4652 3225);
FORCEPROP 2 LAST CDS_LIB mstr_standard
J 0
(-4650 3225);
PAINT ORANGE (-4650 3225);
DISPLAY INVISIBLE (-4650 3225);
FORCEPROP 1 LAST BODY_TYPE PLUMBING
J 0
(-4600 3175);
DISPLAY 2.276596 (-4600 3175);
PAINT GREEN (-4600 3175);
DISPLAY INVISIBLE (-4600 3175);
FORCEPROP 1 LAST HDL_TAP TRUE
J 0
(-4330 3095);
DISPLAY 2.276596 (-4330 3095);
PAINT GREEN (-4330 3095);
DISPLAY INVISIBLE (-4330 3095);
FORCEADD TAP..7
(-4700 3425);
FORCEPROP 3 LASTPIN (-4700 3475) SIG_NAME P3E_CPU0_PE1_SS_C_TXN<2>
J 0
(-4690 3485);
DISPLAY 0.659574 (-4690 3485);
PAINT MONO (-4690 3485);
DISPLAY INVISIBLE (-4690 3485);
FORCEPROP 1 LASTPIN (-4700 3475) BN 2
R 1
J 0
(-4707 3423);
DISPLAY 0.617021 (-4707 3423);
PAINT GREEN (-4707 3423);
FORCEPROP 2 LAST CDS_LIB mstr_standard
J 0
(-4700 3425);
PAINT ORANGE (-4700 3425);
DISPLAY INVISIBLE (-4700 3425);
FORCEPROP 1 LAST BODY_TYPE PLUMBING
J 0
(-4650 3425);
DISPLAY 2.276596 (-4650 3425);
PAINT GREEN (-4650 3425);
DISPLAY INVISIBLE (-4650 3425);
FORCEPROP 1 LAST PATH I426
J 0
(-4702 3425);
DISPLAY 0.872340 (-4702 3425);
PAINT GREEN (-4702 3425);
DISPLAY INVISIBLE (-4702 3425);
FORCEPROP 1 LAST HDL_TAP TRUE
J 0
(-4380 3295);
DISPLAY 2.276596 (-4380 3295);
PAINT GREEN (-4380 3295);
DISPLAY INVISIBLE (-4380 3295);
FORCEADD CAP..1
R 2
(-4650 2975);
FORCEPROP 1 LAST PART_NUMBER A36096-155
J 2
(-4700 2825);
DISPLAY 0.617021 (-4700 2825);
PAINT BLUE (-4700 2825);
FORCEPROP 1 LAST VALUE 0.22UF
J 2
(-4700 3025);
DISPLAY 0.617021 (-4700 3025);
PAINT SKYBLUE (-4700 3025);
FORCEPROP 1 LAST PACK_TYPE 0402
J 2
(-4700 2775);
DISPLAY 0.617021 (-4700 2775);
PAINT SKYBLUE (-4700 2775);
FORCEPROP 1 LAST MATERIAL EMPTY
J 2
(-4700 2875);
DISPLAY 0.617021 (-4700 2875);
PAINT RED (-4700 2875);
FORCEPROP 1 LAST TOLERANCE 10%
J 2
(-4700 2925);
DISPLAY 0.617021 (-4700 2925);
PAINT SKYBLUE (-4700 2925);
FORCEPROP 1 LAST VOLTAGE 16V
J 2
(-4700 2975);
DISPLAY 0.617021 (-4700 2975);
PAINT SKYBLUE (-4700 2975);
FORCEPROP 1 LAST LOCATION C3P19
J 2
(-4700 3075);
DISPLAY 0.617021 (-4700 3075);
PAINT AQUA (-4700 3075);
FORCEPROP 1 LASTPIN (-4650 2875) $PN 2
J 2
(-4660 2855);
DISPLAY 0.787234 (-4660 2855);
PAINT ORANGE (-4660 2855);
DISPLAY INVISIBLE (-4660 2855);
FORCEPROP 2 LAST CDS_LIB mstr_discrete
J 0
(-4650 2975);
PAINT ORANGE (-4650 2975);
DISPLAY INVISIBLE (-4650 2975);
FORCEPROP 1 LASTPIN (-4650 3075) $PN 1
J 2
(-4660 3055);
DISPLAY 0.787234 (-4660 3055);
PAINT ORANGE (-4660 3055);
DISPLAY INVISIBLE (-4660 3055);
FORCEPROP 1 LAST PATH I427
J 2
(-4700 3125);
DISPLAY 0.978723 (-4700 3125);
PAINT WHITE (-4700 3125);
DISPLAY INVISIBLE (-4700 3125);
FORCEPROP 2 LAST CDS_LOCATION C3P19
J 2
(-4700 3075);
DISPLAY 0.617021 (-4700 3075);
PAINT AQUA (-4700 3075);
DISPLAY INVISIBLE (-4700 3075);
FORCEPROP 2 LAST CDS_SEC 1
J 0
(-4700 3175);
DISPLAY 1.021277 (-4700 3175);
PAINT ORANGE (-4700 3175);
DISPLAY INVISIBLE (-4700 3175);
FORCEPROP 2 LAST $SEC 1
J 0
(-4700 3175);
DISPLAY 0.680851 (-4700 3175);
PAINT MONO (-4700 3175);
DISPLAY INVISIBLE (-4700 3175);
FORCEADD TAP..3
(-4850 3225);
FORCEPROP 3 LASTPIN (-4850 3175) SIG_NAME P3E_CPU0_PE1_SS_TXP<3>
J 0
(-4840 3185);
DISPLAY 0.659574 (-4840 3185);
PAINT MONO (-4840 3185);
DISPLAY INVISIBLE (-4840 3185);
FORCEPROP 1 LASTPIN (-4850 3175) BN 3
R 1
J 0
(-4857 3163);
DISPLAY 0.617021 (-4857 3163);
PAINT GREEN (-4857 3163);
FORCEPROP 1 LAST PATH I428
J 0
(-4852 3225);
DISPLAY 0.872340 (-4852 3225);
PAINT GREEN (-4852 3225);
DISPLAY INVISIBLE (-4852 3225);
FORCEPROP 1 LAST BODY_TYPE PLUMBING
J 0
(-4800 3175);
DISPLAY 2.276596 (-4800 3175);
PAINT GREEN (-4800 3175);
DISPLAY INVISIBLE (-4800 3175);
FORCEPROP 2 LAST CDS_LIB mstr_standard
J 0
(-4850 3225);
PAINT ORANGE (-4850 3225);
DISPLAY INVISIBLE (-4850 3225);
FORCEPROP 1 LAST HDL_TAP TRUE
J 0
(-4530 3095);
DISPLAY 2.276596 (-4530 3095);
PAINT GREEN (-4530 3095);
DISPLAY INVISIBLE (-4530 3095);
FORCEADD TAP..7
(-4900 3425);
FORCEPROP 3 LASTPIN (-4900 3475) SIG_NAME P3E_CPU0_PE1_SS_C_TXN<3>
J 0
(-4890 3485);
DISPLAY 0.659574 (-4890 3485);
PAINT MONO (-4890 3485);
DISPLAY INVISIBLE (-4890 3485);
FORCEPROP 1 LASTPIN (-4900 3475) BN 3
R 1
J 0
(-4907 3423);
DISPLAY 0.617021 (-4907 3423);
PAINT GREEN (-4907 3423);
FORCEPROP 1 LAST PATH I429
J 0
(-4902 3425);
DISPLAY 0.872340 (-4902 3425);
PAINT GREEN (-4902 3425);
DISPLAY INVISIBLE (-4902 3425);
FORCEPROP 2 LAST CDS_LIB mstr_standard
J 0
(-4900 3425);
PAINT ORANGE (-4900 3425);
DISPLAY INVISIBLE (-4900 3425);
FORCEPROP 1 LAST BODY_TYPE PLUMBING
J 0
(-4850 3425);
DISPLAY 2.276596 (-4850 3425);
PAINT GREEN (-4850 3425);
DISPLAY INVISIBLE (-4850 3425);
FORCEPROP 1 LAST HDL_TAP TRUE
J 0
(-4580 3295);
DISPLAY 2.276596 (-4580 3295);
PAINT GREEN (-4580 3295);
DISPLAY INVISIBLE (-4580 3295);
FORCEADD TAP..7
(-4250 2425);
FORCEPROP 3 LASTPIN (-4250 2475) SIG_NAME P3E_CPU0_PE1_SS_C_TXP<0>
J 0
(-4240 2485);
DISPLAY 0.659574 (-4240 2485);
PAINT MONO (-4240 2485);
DISPLAY INVISIBLE (-4240 2485);
FORCEPROP 1 LASTPIN (-4250 2475) BN 0
R 1
J 0
(-4257 2423);
DISPLAY 0.617021 (-4257 2423);
PAINT GREEN (-4257 2423);
FORCEPROP 2 LAST CDS_LIB mstr_standard
J 0
(-4250 2425);
PAINT ORANGE (-4250 2425);
DISPLAY INVISIBLE (-4250 2425);
FORCEPROP 1 LAST BODY_TYPE PLUMBING
J 0
(-4200 2425);
DISPLAY 2.276596 (-4200 2425);
PAINT GREEN (-4200 2425);
DISPLAY INVISIBLE (-4200 2425);
FORCEPROP 1 LAST PATH I430
J 0
(-4252 2425);
DISPLAY 0.872340 (-4252 2425);
PAINT GREEN (-4252 2425);
DISPLAY INVISIBLE (-4252 2425);
FORCEPROP 1 LAST HDL_TAP TRUE
J 0
(-3930 2295);
DISPLAY 2.276596 (-3930 2295);
PAINT GREEN (-3930 2295);
DISPLAY INVISIBLE (-3930 2295);
FORCEADD CAP..1
R 2
(-4450 2675);
FORCEPROP 1 LAST MATERIAL EMPTY
J 2
(-4500 2575);
DISPLAY 0.617021 (-4500 2575);
PAINT RED (-4500 2575);
FORCEPROP 1 LAST LOCATION C3P14
J 2
(-4500 2775);
DISPLAY 0.617021 (-4500 2775);
PAINT AQUA (-4500 2775);
FORCEPROP 1 LAST PART_NUMBER A36096-155
J 2
(-4500 2525);
DISPLAY 0.617021 (-4500 2525);
PAINT BLUE (-4500 2525);
FORCEPROP 1 LAST VALUE 0.22UF
J 2
(-4500 2725);
DISPLAY 0.617021 (-4500 2725);
PAINT SKYBLUE (-4500 2725);
FORCEPROP 1 LAST PACK_TYPE 0402
J 2
(-4500 2475);
DISPLAY 0.617021 (-4500 2475);
PAINT SKYBLUE (-4500 2475);
FORCEPROP 1 LAST TOLERANCE 10%
J 2
(-4500 2625);
DISPLAY 0.617021 (-4500 2625);
PAINT SKYBLUE (-4500 2625);
FORCEPROP 1 LAST VOLTAGE 16V
J 2
(-4500 2675);
DISPLAY 0.617021 (-4500 2675);
PAINT SKYBLUE (-4500 2675);
FORCEPROP 1 LASTPIN (-4450 2575) $PN 2
J 2
(-4460 2555);
DISPLAY 0.787234 (-4460 2555);
PAINT ORANGE (-4460 2555);
DISPLAY INVISIBLE (-4460 2555);
FORCEPROP 2 LAST CDS_LOCATION C3P14
J 2
(-4500 2775);
DISPLAY 0.617021 (-4500 2775);
PAINT AQUA (-4500 2775);
DISPLAY INVISIBLE (-4500 2775);
FORCEPROP 2 LAST CDS_LIB mstr_discrete
J 0
(-4450 2675);
PAINT ORANGE (-4450 2675);
DISPLAY INVISIBLE (-4450 2675);
FORCEPROP 1 LASTPIN (-4450 2775) $PN 1
J 2
(-4460 2755);
DISPLAY 0.787234 (-4460 2755);
PAINT ORANGE (-4460 2755);
DISPLAY INVISIBLE (-4460 2755);
FORCEPROP 2 LAST CDS_SEC 1
J 0
(-4500 2875);
DISPLAY 1.021277 (-4500 2875);
PAINT ORANGE (-4500 2875);
DISPLAY INVISIBLE (-4500 2875);
FORCEPROP 2 LAST $SEC 1
J 0
(-4500 2875);
DISPLAY 0.680851 (-4500 2875);
PAINT MONO (-4500 2875);
DISPLAY INVISIBLE (-4500 2875);
FORCEPROP 1 LAST PATH I431
J 2
(-4500 2825);
DISPLAY 0.978723 (-4500 2825);
PAINT WHITE (-4500 2825);
DISPLAY INVISIBLE (-4500 2825);
FORCEADD TAP..7
(-4450 2425);
FORCEPROP 3 LASTPIN (-4450 2475) SIG_NAME P3E_CPU0_PE1_SS_C_TXP<1>
J 0
(-4440 2485);
DISPLAY 0.659574 (-4440 2485);
PAINT MONO (-4440 2485);
DISPLAY INVISIBLE (-4440 2485);
FORCEPROP 1 LASTPIN (-4450 2475) BN 1
R 1
J 0
(-4457 2423);
DISPLAY 0.617021 (-4457 2423);
PAINT GREEN (-4457 2423);
FORCEPROP 2 LAST CDS_LIB mstr_standard
J 0
(-4450 2425);
PAINT ORANGE (-4450 2425);
DISPLAY INVISIBLE (-4450 2425);
FORCEPROP 1 LAST BODY_TYPE PLUMBING
J 0
(-4400 2425);
DISPLAY 2.276596 (-4400 2425);
PAINT GREEN (-4400 2425);
DISPLAY INVISIBLE (-4400 2425);
FORCEPROP 1 LAST PATH I432
J 0
(-4452 2425);
DISPLAY 0.872340 (-4452 2425);
PAINT GREEN (-4452 2425);
DISPLAY INVISIBLE (-4452 2425);
FORCEPROP 1 LAST HDL_TAP TRUE
J 0
(-4130 2295);
DISPLAY 2.276596 (-4130 2295);
PAINT GREEN (-4130 2295);
DISPLAY INVISIBLE (-4130 2295);
FORCEADD OFFPAGE..2
(-4025 2375);
FORCEPROP 2 LAST $XR0 109 
J 0
(-3836 2375);
DISPLAY 0.638298 (-3836 2375);
PAINT MONO (-3836 2375);
FORCEPROP 1 LAST COMMENT_BODY TRUE
J 0
(-4070 2280);
DISPLAY 0.872340 (-4070 2280);
PAINT GREEN (-4070 2280);
DISPLAY INVISIBLE (-4070 2280);
FORCEPROP 2 LAST CDS_LIB mstr_standard
J 0
(-4025 2375);
PAINT ORANGE (-4025 2375);
DISPLAY INVISIBLE (-4025 2375);
FORCEPROP 2 LAST PATH I433
J 0
(-3850 2450);
DISPLAY 1.021277 (-3850 2450);
PAINT ORANGE (-3850 2450);
DISPLAY INVISIBLE (-3850 2450);
FORCEPROP 1 LAST OFFPAGE TRUE
J 0
(-3700 2250);
DISPLAY 0.872340 (-3700 2250);
PAINT GREEN (-3700 2250);
DISPLAY INVISIBLE (-3700 2250);
FORCEADD TAP..7
(-4650 2425);
FORCEPROP 3 LASTPIN (-4650 2475) SIG_NAME P3E_CPU0_PE1_SS_C_TXP<2>
J 0
(-4640 2485);
DISPLAY 0.659574 (-4640 2485);
PAINT MONO (-4640 2485);
DISPLAY INVISIBLE (-4640 2485);
FORCEPROP 1 LASTPIN (-4650 2475) BN 2
R 1
J 0
(-4657 2423);
DISPLAY 0.617021 (-4657 2423);
PAINT GREEN (-4657 2423);
FORCEPROP 2 LAST CDS_LIB mstr_standard
J 0
(-4650 2425);
PAINT ORANGE (-4650 2425);
DISPLAY INVISIBLE (-4650 2425);
FORCEPROP 1 LAST PATH I434
J 0
(-4652 2425);
DISPLAY 0.872340 (-4652 2425);
PAINT GREEN (-4652 2425);
DISPLAY INVISIBLE (-4652 2425);
FORCEPROP 1 LAST BODY_TYPE PLUMBING
J 0
(-4600 2425);
DISPLAY 2.276596 (-4600 2425);
PAINT GREEN (-4600 2425);
DISPLAY INVISIBLE (-4600 2425);
FORCEPROP 1 LAST HDL_TAP TRUE
J 0
(-4330 2295);
DISPLAY 2.276596 (-4330 2295);
PAINT GREEN (-4330 2295);
DISPLAY INVISIBLE (-4330 2295);
FORCEADD CAP..1
R 2
(-4850 2675);
FORCEPROP 1 LAST PART_NUMBER A36096-155
J 2
(-4900 2525);
DISPLAY 0.617021 (-4900 2525);
PAINT BLUE (-4900 2525);
FORCEPROP 1 LAST PACK_TYPE 0402
J 2
(-4900 2475);
DISPLAY 0.617021 (-4900 2475);
PAINT SKYBLUE (-4900 2475);
FORCEPROP 1 LAST MATERIAL EMPTY
J 2
(-4900 2575);
DISPLAY 0.617021 (-4900 2575);
PAINT RED (-4900 2575);
FORCEPROP 1 LAST LOCATION C3P22
J 2
(-4900 2775);
DISPLAY 0.617021 (-4900 2775);
PAINT AQUA (-4900 2775);
FORCEPROP 1 LAST VALUE 0.22UF
J 2
(-4900 2725);
DISPLAY 0.617021 (-4900 2725);
PAINT SKYBLUE (-4900 2725);
FORCEPROP 1 LAST TOLERANCE 10%
J 2
(-4900 2625);
DISPLAY 0.617021 (-4900 2625);
PAINT SKYBLUE (-4900 2625);
FORCEPROP 1 LAST VOLTAGE 16V
J 2
(-4900 2675);
DISPLAY 0.617021 (-4900 2675);
PAINT SKYBLUE (-4900 2675);
FORCEPROP 1 LASTPIN (-4850 2575) $PN 2
J 2
(-4860 2555);
DISPLAY 0.787234 (-4860 2555);
PAINT ORANGE (-4860 2555);
DISPLAY INVISIBLE (-4860 2555);
FORCEPROP 2 LAST CDS_LOCATION C3P22
J 2
(-4900 2775);
DISPLAY 0.617021 (-4900 2775);
PAINT AQUA (-4900 2775);
DISPLAY INVISIBLE (-4900 2775);
FORCEPROP 2 LAST CDS_SEC 1
J 0
(-4900 2875);
DISPLAY 1.021277 (-4900 2875);
PAINT ORANGE (-4900 2875);
DISPLAY INVISIBLE (-4900 2875);
FORCEPROP 2 LAST $SEC 1
J 0
(-4900 2875);
DISPLAY 0.680851 (-4900 2875);
PAINT MONO (-4900 2875);
DISPLAY INVISIBLE (-4900 2875);
FORCEPROP 1 LAST PATH I435
J 2
(-4900 2825);
DISPLAY 0.978723 (-4900 2825);
PAINT WHITE (-4900 2825);
DISPLAY INVISIBLE (-4900 2825);
FORCEPROP 2 LAST CDS_LIB mstr_discrete
J 0
(-4850 2675);
PAINT ORANGE (-4850 2675);
DISPLAY INVISIBLE (-4850 2675);
FORCEPROP 1 LASTPIN (-4850 2775) $PN 1
J 2
(-4860 2755);
DISPLAY 0.787234 (-4860 2755);
PAINT ORANGE (-4860 2755);
DISPLAY INVISIBLE (-4860 2755);
FORCEADD TAP..7
(-4850 2425);
FORCEPROP 3 LASTPIN (-4850 2475) SIG_NAME P3E_CPU0_PE1_SS_C_TXP<3>
J 0
(-4840 2485);
DISPLAY 0.659574 (-4840 2485);
PAINT MONO (-4840 2485);
DISPLAY INVISIBLE (-4840 2485);
FORCEPROP 1 LASTPIN (-4850 2475) BN 3
R 1
J 0
(-4857 2423);
DISPLAY 0.617021 (-4857 2423);
PAINT GREEN (-4857 2423);
FORCEPROP 2 LAST CDS_LIB mstr_standard
J 0
(-4850 2425);
PAINT ORANGE (-4850 2425);
DISPLAY INVISIBLE (-4850 2425);
FORCEPROP 1 LAST BODY_TYPE PLUMBING
J 0
(-4800 2425);
DISPLAY 2.276596 (-4800 2425);
PAINT GREEN (-4800 2425);
DISPLAY INVISIBLE (-4800 2425);
FORCEPROP 1 LAST PATH I436
J 0
(-4852 2425);
DISPLAY 0.872340 (-4852 2425);
PAINT GREEN (-4852 2425);
DISPLAY INVISIBLE (-4852 2425);
FORCEPROP 1 LAST HDL_TAP TRUE
J 0
(-4530 2295);
DISPLAY 2.276596 (-4530 2295);
PAINT GREEN (-4530 2295);
DISPLAY INVISIBLE (-4530 2295);
FORCEADD CAP..1
R 2
(-5100 3975);
FORCEPROP 1 LAST PART_NUMBER A36096-155
J 2
(-5150 3825);
DISPLAY 0.617021 (-5150 3825);
PAINT BLUE (-5150 3825);
FORCEPROP 1 LAST PACK_TYPE 0402
J 2
(-5150 3775);
DISPLAY 0.617021 (-5150 3775);
PAINT SKYBLUE (-5150 3775);
FORCEPROP 1 LAST MATERIAL EMPTY
J 2
(-5150 3875);
DISPLAY 0.617021 (-5150 3875);
PAINT RED (-5150 3875);
FORCEPROP 1 LAST VALUE 0.22UF
J 2
(-5150 4025);
DISPLAY 0.617021 (-5150 4025);
PAINT SKYBLUE (-5150 4025);
FORCEPROP 1 LAST TOLERANCE 10%
J 2
(-5150 3925);
DISPLAY 0.617021 (-5150 3925);
PAINT SKYBLUE (-5150 3925);
FORCEPROP 1 LAST VOLTAGE 16V
J 2
(-5150 3975);
DISPLAY 0.617021 (-5150 3975);
PAINT SKYBLUE (-5150 3975);
FORCEPROP 1 LAST LOCATION C3P29
J 2
(-5150 4075);
DISPLAY 0.617021 (-5150 4075);
PAINT AQUA (-5150 4075);
FORCEPROP 1 LASTPIN (-5100 3875) $PN 2
J 2
(-5110 3855);
DISPLAY 0.787234 (-5110 3855);
PAINT ORANGE (-5110 3855);
DISPLAY INVISIBLE (-5110 3855);
FORCEPROP 1 LASTPIN (-5100 4075) $PN 1
J 2
(-5110 4055);
DISPLAY 0.787234 (-5110 4055);
PAINT ORANGE (-5110 4055);
DISPLAY INVISIBLE (-5110 4055);
FORCEPROP 2 LAST CDS_LIB mstr_discrete
J 0
(-5100 3975);
PAINT ORANGE (-5100 3975);
DISPLAY INVISIBLE (-5100 3975);
FORCEPROP 2 LAST CDS_LOCATION C3P29
J 2
(-5150 4075);
DISPLAY 0.617021 (-5150 4075);
PAINT AQUA (-5150 4075);
DISPLAY INVISIBLE (-5150 4075);
FORCEPROP 2 LAST CDS_SEC 1
J 0
(-5150 4175);
DISPLAY 1.021277 (-5150 4175);
PAINT ORANGE (-5150 4175);
DISPLAY INVISIBLE (-5150 4175);
FORCEPROP 2 LAST $SEC 1
J 0
(-5150 4175);
DISPLAY 0.680851 (-5150 4175);
PAINT MONO (-5150 4175);
DISPLAY INVISIBLE (-5150 4175);
FORCEPROP 1 LAST PATH I437
J 2
(-5150 4125);
DISPLAY 0.978723 (-5150 4125);
PAINT WHITE (-5150 4125);
DISPLAY INVISIBLE (-5150 4125);
FORCEADD CAP..1
R 2
(-5500 3975);
FORCEPROP 1 LAST MATERIAL EMPTY
J 2
(-5550 3875);
DISPLAY 0.617021 (-5550 3875);
PAINT RED (-5550 3875);
FORCEPROP 1 LAST PART_NUMBER A36096-155
J 2
(-5550 3825);
DISPLAY 0.617021 (-5550 3825);
PAINT BLUE (-5550 3825);
FORCEPROP 1 LAST VALUE 0.22UF
J 2
(-5550 4025);
DISPLAY 0.617021 (-5550 4025);
PAINT SKYBLUE (-5550 4025);
FORCEPROP 1 LAST TOLERANCE 10%
J 2
(-5550 3925);
DISPLAY 0.617021 (-5550 3925);
PAINT SKYBLUE (-5550 3925);
FORCEPROP 1 LAST PACK_TYPE 0402
J 2
(-5550 3775);
DISPLAY 0.617021 (-5550 3775);
PAINT SKYBLUE (-5550 3775);
FORCEPROP 1 LAST VOLTAGE 16V
J 2
(-5550 3975);
DISPLAY 0.617021 (-5550 3975);
PAINT SKYBLUE (-5550 3975);
FORCEPROP 1 LAST LOCATION C3P36
J 2
(-5550 4075);
DISPLAY 0.617021 (-5550 4075);
PAINT AQUA (-5550 4075);
FORCEPROP 1 LASTPIN (-5500 3875) $PN 2
J 2
(-5510 3855);
DISPLAY 0.787234 (-5510 3855);
PAINT ORANGE (-5510 3855);
DISPLAY INVISIBLE (-5510 3855);
FORCEPROP 1 LASTPIN (-5500 4075) $PN 1
J 2
(-5510 4055);
DISPLAY 0.787234 (-5510 4055);
PAINT ORANGE (-5510 4055);
DISPLAY INVISIBLE (-5510 4055);
FORCEPROP 2 LAST CDS_LIB mstr_discrete
J 0
(-5500 3975);
PAINT ORANGE (-5500 3975);
DISPLAY INVISIBLE (-5500 3975);
FORCEPROP 2 LAST CDS_LOCATION C3P36
J 2
(-5550 4075);
DISPLAY 0.617021 (-5550 4075);
PAINT AQUA (-5550 4075);
DISPLAY INVISIBLE (-5550 4075);
FORCEPROP 2 LAST CDS_SEC 1
J 0
(-5550 4175);
DISPLAY 1.021277 (-5550 4175);
PAINT ORANGE (-5550 4175);
DISPLAY INVISIBLE (-5550 4175);
FORCEPROP 2 LAST $SEC 1
J 0
(-5550 4175);
DISPLAY 0.680851 (-5550 4175);
PAINT MONO (-5550 4175);
DISPLAY INVISIBLE (-5550 4175);
FORCEPROP 1 LAST PATH I438
J 2
(-5550 4125);
DISPLAY 0.978723 (-5550 4125);
PAINT WHITE (-5550 4125);
DISPLAY INVISIBLE (-5550 4125);
FORCEADD CAP..1
R 2
(-5300 3675);
FORCEPROP 1 LAST PART_NUMBER A36096-155
J 2
(-5350 3525);
DISPLAY 0.617021 (-5350 3525);
PAINT BLUE (-5350 3525);
FORCEPROP 1 LAST PACK_TYPE 0402
J 2
(-5350 3475);
DISPLAY 0.617021 (-5350 3475);
PAINT SKYBLUE (-5350 3475);
FORCEPROP 1 LAST MATERIAL EMPTY
J 2
(-5350 3575);
DISPLAY 0.617021 (-5350 3575);
PAINT RED (-5350 3575);
FORCEPROP 1 LAST LOCATION C3P33
J 2
(-5350 3775);
DISPLAY 0.617021 (-5350 3775);
PAINT AQUA (-5350 3775);
FORCEPROP 1 LAST VALUE 0.22UF
J 2
(-5350 3725);
DISPLAY 0.617021 (-5350 3725);
PAINT SKYBLUE (-5350 3725);
FORCEPROP 1 LAST TOLERANCE 10%
J 2
(-5350 3625);
DISPLAY 0.617021 (-5350 3625);
PAINT SKYBLUE (-5350 3625);
FORCEPROP 1 LAST VOLTAGE 16V
J 2
(-5350 3675);
DISPLAY 0.617021 (-5350 3675);
PAINT SKYBLUE (-5350 3675);
FORCEPROP 1 LASTPIN (-5300 3575) $PN 2
J 2
(-5310 3555);
DISPLAY 0.787234 (-5310 3555);
PAINT ORANGE (-5310 3555);
DISPLAY INVISIBLE (-5310 3555);
FORCEPROP 2 LAST CDS_LIB mstr_discrete
J 0
(-5300 3675);
PAINT ORANGE (-5300 3675);
DISPLAY INVISIBLE (-5300 3675);
FORCEPROP 1 LASTPIN (-5300 3775) $PN 1
J 2
(-5310 3755);
DISPLAY 0.787234 (-5310 3755);
PAINT ORANGE (-5310 3755);
DISPLAY INVISIBLE (-5310 3755);
FORCEPROP 2 LAST CDS_LOCATION C3P33
J 2
(-5350 3775);
DISPLAY 0.617021 (-5350 3775);
PAINT AQUA (-5350 3775);
DISPLAY INVISIBLE (-5350 3775);
FORCEPROP 1 LAST PATH I439
J 2
(-5350 3825);
DISPLAY 0.978723 (-5350 3825);
PAINT WHITE (-5350 3825);
DISPLAY INVISIBLE (-5350 3825);
FORCEPROP 2 LAST CDS_SEC 1
J 0
(-5350 3875);
DISPLAY 1.021277 (-5350 3875);
PAINT ORANGE (-5350 3875);
DISPLAY INVISIBLE (-5350 3875);
FORCEPROP 2 LAST $SEC 1
J 0
(-5350 3875);
DISPLAY 0.680851 (-5350 3875);
PAINT MONO (-5350 3875);
DISPLAY INVISIBLE (-5350 3875);
FORCEADD TAP..7
(-5100 3425);
FORCEPROP 3 LASTPIN (-5100 3475) SIG_NAME P3E_CPU0_PE1_SS_C_TXN<4>
J 0
(-5090 3485);
DISPLAY 0.659574 (-5090 3485);
PAINT MONO (-5090 3485);
DISPLAY INVISIBLE (-5090 3485);
FORCEPROP 1 LASTPIN (-5100 3475) BN 4
R 1
J 0
(-5107 3423);
DISPLAY 0.617021 (-5107 3423);
PAINT GREEN (-5107 3423);
FORCEPROP 2 LAST CDS_LIB mstr_standard
J 0
(-5100 3425);
PAINT ORANGE (-5100 3425);
DISPLAY INVISIBLE (-5100 3425);
FORCEPROP 1 LAST BODY_TYPE PLUMBING
J 0
(-5050 3425);
DISPLAY 2.276596 (-5050 3425);
PAINT GREEN (-5050 3425);
DISPLAY INVISIBLE (-5050 3425);
FORCEPROP 1 LAST PATH I440
J 0
(-5102 3425);
DISPLAY 0.872340 (-5102 3425);
PAINT GREEN (-5102 3425);
DISPLAY INVISIBLE (-5102 3425);
FORCEPROP 1 LAST HDL_TAP TRUE
J 0
(-4780 3295);
DISPLAY 2.276596 (-4780 3295);
PAINT GREEN (-4780 3295);
DISPLAY INVISIBLE (-4780 3295);
FORCEADD TAP..3
(-5050 3225);
FORCEPROP 3 LASTPIN (-5050 3175) SIG_NAME P3E_CPU0_PE1_SS_TXP<4>
J 0
(-5040 3185);
DISPLAY 0.659574 (-5040 3185);
PAINT MONO (-5040 3185);
DISPLAY INVISIBLE (-5040 3185);
FORCEPROP 1 LASTPIN (-5050 3175) BN 4
R 1
J 0
(-5057 3163);
DISPLAY 0.617021 (-5057 3163);
PAINT GREEN (-5057 3163);
FORCEPROP 1 LAST BODY_TYPE PLUMBING
J 0
(-5000 3175);
DISPLAY 2.276596 (-5000 3175);
PAINT GREEN (-5000 3175);
DISPLAY INVISIBLE (-5000 3175);
FORCEPROP 2 LAST CDS_LIB mstr_standard
J 0
(-5050 3225);
PAINT ORANGE (-5050 3225);
DISPLAY INVISIBLE (-5050 3225);
FORCEPROP 1 LAST PATH I441
J 0
(-5052 3225);
DISPLAY 0.872340 (-5052 3225);
PAINT GREEN (-5052 3225);
DISPLAY INVISIBLE (-5052 3225);
FORCEPROP 1 LAST HDL_TAP TRUE
J 0
(-4730 3095);
DISPLAY 2.276596 (-4730 3095);
PAINT GREEN (-4730 3095);
DISPLAY INVISIBLE (-4730 3095);
FORCEADD TAP..7
(-5300 3425);
FORCEPROP 3 LASTPIN (-5300 3475) SIG_NAME P3E_CPU0_PE1_SS_C_TXN<5>
J 0
(-5290 3485);
DISPLAY 0.659574 (-5290 3485);
PAINT MONO (-5290 3485);
DISPLAY INVISIBLE (-5290 3485);
FORCEPROP 1 LASTPIN (-5300 3475) BN 5
R 1
J 0
(-5307 3423);
DISPLAY 0.617021 (-5307 3423);
PAINT GREEN (-5307 3423);
FORCEPROP 2 LAST CDS_LIB mstr_standard
J 0
(-5300 3425);
PAINT ORANGE (-5300 3425);
DISPLAY INVISIBLE (-5300 3425);
FORCEPROP 1 LAST BODY_TYPE PLUMBING
J 0
(-5250 3425);
DISPLAY 2.276596 (-5250 3425);
PAINT GREEN (-5250 3425);
DISPLAY INVISIBLE (-5250 3425);
FORCEPROP 1 LAST PATH I442
J 0
(-5302 3425);
DISPLAY 0.872340 (-5302 3425);
PAINT GREEN (-5302 3425);
DISPLAY INVISIBLE (-5302 3425);
FORCEPROP 1 LAST HDL_TAP TRUE
J 0
(-4980 3295);
DISPLAY 2.276596 (-4980 3295);
PAINT GREEN (-4980 3295);
DISPLAY INVISIBLE (-4980 3295);
FORCEADD TAP..3
(-5250 3225);
FORCEPROP 3 LASTPIN (-5250 3175) SIG_NAME P3E_CPU0_PE1_SS_TXP<5>
J 0
(-5240 3185);
DISPLAY 0.659574 (-5240 3185);
PAINT MONO (-5240 3185);
DISPLAY INVISIBLE (-5240 3185);
FORCEPROP 1 LASTPIN (-5250 3175) BN 5
R 1
J 0
(-5257 3163);
DISPLAY 0.617021 (-5257 3163);
PAINT GREEN (-5257 3163);
FORCEPROP 2 LAST CDS_LIB mstr_standard
J 0
(-5250 3225);
PAINT ORANGE (-5250 3225);
DISPLAY INVISIBLE (-5250 3225);
FORCEPROP 1 LAST BODY_TYPE PLUMBING
J 0
(-5200 3175);
DISPLAY 2.276596 (-5200 3175);
PAINT GREEN (-5200 3175);
DISPLAY INVISIBLE (-5200 3175);
FORCEPROP 1 LAST PATH I443
J 0
(-5252 3225);
DISPLAY 0.872340 (-5252 3225);
PAINT GREEN (-5252 3225);
DISPLAY INVISIBLE (-5252 3225);
FORCEPROP 1 LAST HDL_TAP TRUE
J 0
(-4930 3095);
DISPLAY 2.276596 (-4930 3095);
PAINT GREEN (-4930 3095);
DISPLAY INVISIBLE (-4930 3095);
FORCEADD CAP..1
R 2
(-5050 2975);
FORCEPROP 1 LAST MATERIAL EMPTY
J 2
(-5100 2875);
DISPLAY 0.617021 (-5100 2875);
PAINT RED (-5100 2875);
FORCEPROP 1 LAST LOCATION C3P26
J 2
(-5100 3075);
DISPLAY 0.617021 (-5100 3075);
PAINT AQUA (-5100 3075);
FORCEPROP 1 LAST PART_NUMBER A36096-155
J 2
(-5100 2825);
DISPLAY 0.617021 (-5100 2825);
PAINT BLUE (-5100 2825);
FORCEPROP 1 LAST VALUE 0.22UF
J 2
(-5100 3025);
DISPLAY 0.617021 (-5100 3025);
PAINT SKYBLUE (-5100 3025);
FORCEPROP 1 LAST TOLERANCE 10%
J 2
(-5100 2925);
DISPLAY 0.617021 (-5100 2925);
PAINT SKYBLUE (-5100 2925);
FORCEPROP 1 LAST PACK_TYPE 0402
J 2
(-5100 2775);
DISPLAY 0.617021 (-5100 2775);
PAINT SKYBLUE (-5100 2775);
FORCEPROP 1 LAST VOLTAGE 16V
J 2
(-5100 2975);
DISPLAY 0.617021 (-5100 2975);
PAINT SKYBLUE (-5100 2975);
FORCEPROP 1 LASTPIN (-5050 2875) $PN 2
J 2
(-5060 2855);
DISPLAY 0.787234 (-5060 2855);
PAINT ORANGE (-5060 2855);
DISPLAY INVISIBLE (-5060 2855);
FORCEPROP 2 LAST CDS_LIB mstr_discrete
J 0
(-5050 2975);
PAINT ORANGE (-5050 2975);
DISPLAY INVISIBLE (-5050 2975);
FORCEPROP 1 LASTPIN (-5050 3075) $PN 1
J 2
(-5060 3055);
DISPLAY 0.787234 (-5060 3055);
PAINT ORANGE (-5060 3055);
DISPLAY INVISIBLE (-5060 3055);
FORCEPROP 2 LAST CDS_LOCATION C3P26
J 2
(-5100 3075);
DISPLAY 0.617021 (-5100 3075);
PAINT AQUA (-5100 3075);
DISPLAY INVISIBLE (-5100 3075);
FORCEPROP 1 LAST PATH I444
J 2
(-5100 3125);
DISPLAY 0.978723 (-5100 3125);
PAINT WHITE (-5100 3125);
DISPLAY INVISIBLE (-5100 3125);
FORCEPROP 2 LAST CDS_SEC 1
J 0
(-5100 3175);
DISPLAY 1.021277 (-5100 3175);
PAINT ORANGE (-5100 3175);
DISPLAY INVISIBLE (-5100 3175);
FORCEPROP 2 LAST $SEC 1
J 0
(-5100 3175);
DISPLAY 0.680851 (-5100 3175);
PAINT MONO (-5100 3175);
DISPLAY INVISIBLE (-5100 3175);
FORCEADD TAP..7
(-5500 3425);
FORCEPROP 3 LASTPIN (-5500 3475) SIG_NAME P3E_CPU0_PE1_SS_C_TXN<6>
J 0
(-5490 3485);
DISPLAY 0.659574 (-5490 3485);
PAINT MONO (-5490 3485);
DISPLAY INVISIBLE (-5490 3485);
FORCEPROP 1 LASTPIN (-5500 3475) BN 6
R 1
J 0
(-5507 3423);
DISPLAY 0.617021 (-5507 3423);
PAINT GREEN (-5507 3423);
FORCEPROP 2 LAST CDS_LIB mstr_standard
J 0
(-5500 3425);
PAINT ORANGE (-5500 3425);
DISPLAY INVISIBLE (-5500 3425);
FORCEPROP 1 LAST BODY_TYPE PLUMBING
J 0
(-5450 3425);
DISPLAY 2.276596 (-5450 3425);
PAINT GREEN (-5450 3425);
DISPLAY INVISIBLE (-5450 3425);
FORCEPROP 1 LAST PATH I445
J 0
(-5502 3425);
DISPLAY 0.872340 (-5502 3425);
PAINT GREEN (-5502 3425);
DISPLAY INVISIBLE (-5502 3425);
FORCEPROP 1 LAST HDL_TAP TRUE
J 0
(-5180 3295);
DISPLAY 2.276596 (-5180 3295);
PAINT GREEN (-5180 3295);
DISPLAY INVISIBLE (-5180 3295);
FORCEADD TAP..3
(-5450 3225);
FORCEPROP 3 LASTPIN (-5450 3175) SIG_NAME P3E_CPU0_PE1_SS_TXP<6>
J 0
(-5440 3185);
DISPLAY 0.659574 (-5440 3185);
PAINT MONO (-5440 3185);
DISPLAY INVISIBLE (-5440 3185);
FORCEPROP 1 LASTPIN (-5450 3175) BN 6
R 1
J 0
(-5457 3163);
DISPLAY 0.617021 (-5457 3163);
PAINT GREEN (-5457 3163);
FORCEPROP 1 LAST BODY_TYPE PLUMBING
J 0
(-5400 3175);
DISPLAY 2.276596 (-5400 3175);
PAINT GREEN (-5400 3175);
DISPLAY INVISIBLE (-5400 3175);
FORCEPROP 1 LAST PATH I446
J 0
(-5452 3225);
DISPLAY 0.872340 (-5452 3225);
PAINT GREEN (-5452 3225);
DISPLAY INVISIBLE (-5452 3225);
FORCEPROP 2 LAST CDS_LIB mstr_standard
J 0
(-5450 3225);
PAINT ORANGE (-5450 3225);
DISPLAY INVISIBLE (-5450 3225);
FORCEPROP 1 LAST HDL_TAP TRUE
J 0
(-5130 3095);
DISPLAY 2.276596 (-5130 3095);
PAINT GREEN (-5130 3095);
DISPLAY INVISIBLE (-5130 3095);
FORCEADD CAP..1
R 2
(-5450 2975);
FORCEPROP 1 LAST MATERIAL EMPTY
J 2
(-5500 2875);
DISPLAY 0.617021 (-5500 2875);
PAINT RED (-5500 2875);
FORCEPROP 1 LAST PART_NUMBER A36096-155
J 2
(-5500 2825);
DISPLAY 0.617021 (-5500 2825);
PAINT BLUE (-5500 2825);
FORCEPROP 1 LAST VALUE 0.22UF
J 2
(-5500 3025);
DISPLAY 0.617021 (-5500 3025);
PAINT SKYBLUE (-5500 3025);
FORCEPROP 1 LAST PACK_TYPE 0402
J 2
(-5500 2775);
DISPLAY 0.617021 (-5500 2775);
PAINT SKYBLUE (-5500 2775);
FORCEPROP 1 LAST TOLERANCE 10%
J 2
(-5500 2925);
DISPLAY 0.617021 (-5500 2925);
PAINT SKYBLUE (-5500 2925);
FORCEPROP 1 LAST VOLTAGE 16V
J 2
(-5500 2975);
DISPLAY 0.617021 (-5500 2975);
PAINT SKYBLUE (-5500 2975);
FORCEPROP 1 LAST LOCATION C3P34
J 2
(-5500 3075);
DISPLAY 0.617021 (-5500 3075);
PAINT AQUA (-5500 3075);
FORCEPROP 1 LASTPIN (-5450 2875) $PN 2
J 2
(-5460 2855);
DISPLAY 0.787234 (-5460 2855);
PAINT ORANGE (-5460 2855);
DISPLAY INVISIBLE (-5460 2855);
FORCEPROP 2 LAST CDS_LIB mstr_discrete
J 0
(-5450 2975);
PAINT ORANGE (-5450 2975);
DISPLAY INVISIBLE (-5450 2975);
FORCEPROP 1 LASTPIN (-5450 3075) $PN 1
J 2
(-5460 3055);
DISPLAY 0.787234 (-5460 3055);
PAINT ORANGE (-5460 3055);
DISPLAY INVISIBLE (-5460 3055);
FORCEPROP 2 LAST CDS_LOCATION C3P34
J 2
(-5500 3075);
DISPLAY 0.617021 (-5500 3075);
PAINT AQUA (-5500 3075);
DISPLAY INVISIBLE (-5500 3075);
FORCEPROP 1 LAST PATH I447
J 2
(-5500 3125);
DISPLAY 0.978723 (-5500 3125);
PAINT WHITE (-5500 3125);
DISPLAY INVISIBLE (-5500 3125);
FORCEPROP 2 LAST $SEC 1
J 0
(-5500 3175);
DISPLAY 0.680851 (-5500 3175);
PAINT MONO (-5500 3175);
DISPLAY INVISIBLE (-5500 3175);
FORCEPROP 2 LAST CDS_SEC 1
J 0
(-5500 3175);
DISPLAY 1.021277 (-5500 3175);
PAINT ORANGE (-5500 3175);
DISPLAY INVISIBLE (-5500 3175);
FORCEADD CAP..1
R 2
(-5700 3675);
FORCEPROP 1 LAST PART_NUMBER A36096-155
J 2
(-5750 3525);
DISPLAY 0.617021 (-5750 3525);
PAINT BLUE (-5750 3525);
FORCEPROP 1 LAST PACK_TYPE 0402
J 2
(-5750 3475);
DISPLAY 0.617021 (-5750 3475);
PAINT SKYBLUE (-5750 3475);
FORCEPROP 1 LAST MATERIAL EMPTY
J 2
(-5750 3575);
DISPLAY 0.617021 (-5750 3575);
PAINT RED (-5750 3575);
FORCEPROP 1 LAST LOCATION C3P41
J 2
(-5750 3775);
DISPLAY 0.617021 (-5750 3775);
PAINT AQUA (-5750 3775);
FORCEPROP 1 LAST VALUE 0.22UF
J 2
(-5750 3725);
DISPLAY 0.617021 (-5750 3725);
PAINT SKYBLUE (-5750 3725);
FORCEPROP 1 LAST TOLERANCE 10%
J 2
(-5750 3625);
DISPLAY 0.617021 (-5750 3625);
PAINT SKYBLUE (-5750 3625);
FORCEPROP 1 LAST VOLTAGE 16V
J 2
(-5750 3675);
DISPLAY 0.617021 (-5750 3675);
PAINT SKYBLUE (-5750 3675);
FORCEPROP 1 LASTPIN (-5700 3575) $PN 2
J 2
(-5710 3555);
DISPLAY 0.787234 (-5710 3555);
PAINT ORANGE (-5710 3555);
DISPLAY INVISIBLE (-5710 3555);
FORCEPROP 2 LAST CDS_LIB mstr_discrete
J 0
(-5700 3675);
PAINT ORANGE (-5700 3675);
DISPLAY INVISIBLE (-5700 3675);
FORCEPROP 2 LAST CDS_LOCATION C3P41
J 2
(-5750 3775);
DISPLAY 0.617021 (-5750 3775);
PAINT AQUA (-5750 3775);
DISPLAY INVISIBLE (-5750 3775);
FORCEPROP 1 LASTPIN (-5700 3775) $PN 1
J 2
(-5710 3755);
DISPLAY 0.787234 (-5710 3755);
PAINT ORANGE (-5710 3755);
DISPLAY INVISIBLE (-5710 3755);
FORCEPROP 1 LAST PATH I448
J 2
(-5750 3825);
DISPLAY 0.978723 (-5750 3825);
PAINT WHITE (-5750 3825);
DISPLAY INVISIBLE (-5750 3825);
FORCEPROP 2 LAST CDS_SEC 1
J 0
(-5750 3875);
DISPLAY 1.021277 (-5750 3875);
PAINT ORANGE (-5750 3875);
DISPLAY INVISIBLE (-5750 3875);
FORCEPROP 2 LAST $SEC 1
J 0
(-5750 3875);
DISPLAY 0.680851 (-5750 3875);
PAINT MONO (-5750 3875);
DISPLAY INVISIBLE (-5750 3875);
FORCEADD TAP..3
(-5650 3225);
FORCEPROP 3 LASTPIN (-5650 3175) SIG_NAME P3E_CPU0_PE1_SS_TXP<7>
J 0
(-5640 3185);
DISPLAY 0.659574 (-5640 3185);
PAINT MONO (-5640 3185);
DISPLAY INVISIBLE (-5640 3185);
FORCEPROP 1 LASTPIN (-5650 3175) BN 7
R 1
J 0
(-5657 3163);
DISPLAY 0.617021 (-5657 3163);
PAINT GREEN (-5657 3163);
FORCEPROP 2 LAST CDS_LIB mstr_standard
J 0
(-5650 3225);
PAINT ORANGE (-5650 3225);
DISPLAY INVISIBLE (-5650 3225);
FORCEPROP 1 LAST PATH I449
J 0
(-5652 3225);
DISPLAY 0.872340 (-5652 3225);
PAINT GREEN (-5652 3225);
DISPLAY INVISIBLE (-5652 3225);
FORCEPROP 1 LAST BODY_TYPE PLUMBING
J 0
(-5600 3175);
DISPLAY 2.276596 (-5600 3175);
PAINT GREEN (-5600 3175);
DISPLAY INVISIBLE (-5600 3175);
FORCEPROP 1 LAST HDL_TAP TRUE
J 0
(-5330 3095);
DISPLAY 2.276596 (-5330 3095);
PAINT GREEN (-5330 3095);
DISPLAY INVISIBLE (-5330 3095);
FORCEADD TAP..7
(-5700 3425);
FORCEPROP 3 LASTPIN (-5700 3475) SIG_NAME P3E_CPU0_PE1_SS_C_TXN<7>
J 0
(-5690 3485);
DISPLAY 0.659574 (-5690 3485);
PAINT MONO (-5690 3485);
DISPLAY INVISIBLE (-5690 3485);
FORCEPROP 1 LASTPIN (-5700 3475) BN 7
R 1
J 0
(-5707 3423);
DISPLAY 0.617021 (-5707 3423);
PAINT GREEN (-5707 3423);
FORCEPROP 2 LAST CDS_LIB mstr_standard
J 0
(-5700 3425);
PAINT ORANGE (-5700 3425);
DISPLAY INVISIBLE (-5700 3425);
FORCEPROP 1 LAST BODY_TYPE PLUMBING
J 0
(-5650 3425);
DISPLAY 2.276596 (-5650 3425);
PAINT GREEN (-5650 3425);
DISPLAY INVISIBLE (-5650 3425);
FORCEPROP 1 LAST PATH I450
J 0
(-5702 3425);
DISPLAY 0.872340 (-5702 3425);
PAINT GREEN (-5702 3425);
DISPLAY INVISIBLE (-5702 3425);
FORCEPROP 1 LAST HDL_TAP TRUE
J 0
(-5380 3295);
DISPLAY 2.276596 (-5380 3295);
PAINT GREEN (-5380 3295);
DISPLAY INVISIBLE (-5380 3295);
FORCEADD TAP..7
(-5050 2425);
FORCEPROP 3 LASTPIN (-5050 2475) SIG_NAME P3E_CPU0_PE1_SS_C_TXP<4>
J 0
(-5040 2485);
DISPLAY 0.659574 (-5040 2485);
PAINT MONO (-5040 2485);
DISPLAY INVISIBLE (-5040 2485);
FORCEPROP 1 LASTPIN (-5050 2475) BN 4
R 1
J 0
(-5057 2423);
DISPLAY 0.617021 (-5057 2423);
PAINT GREEN (-5057 2423);
FORCEPROP 2 LAST CDS_LIB mstr_standard
J 0
(-5050 2425);
PAINT ORANGE (-5050 2425);
DISPLAY INVISIBLE (-5050 2425);
FORCEPROP 1 LAST BODY_TYPE PLUMBING
J 0
(-5000 2425);
DISPLAY 2.276596 (-5000 2425);
PAINT GREEN (-5000 2425);
DISPLAY INVISIBLE (-5000 2425);
FORCEPROP 1 LAST PATH I451
J 0
(-5052 2425);
DISPLAY 0.872340 (-5052 2425);
PAINT GREEN (-5052 2425);
DISPLAY INVISIBLE (-5052 2425);
FORCEPROP 1 LAST HDL_TAP TRUE
J 0
(-4730 2295);
DISPLAY 2.276596 (-4730 2295);
PAINT GREEN (-4730 2295);
DISPLAY INVISIBLE (-4730 2295);
FORCEADD CAP..1
R 2
(-5250 2675);
FORCEPROP 1 LAST PART_NUMBER A36096-155
J 2
(-5300 2525);
DISPLAY 0.617021 (-5300 2525);
PAINT BLUE (-5300 2525);
FORCEPROP 1 LAST PACK_TYPE 0402
J 2
(-5300 2475);
DISPLAY 0.617021 (-5300 2475);
PAINT SKYBLUE (-5300 2475);
FORCEPROP 1 LAST MATERIAL EMPTY
J 2
(-5300 2575);
DISPLAY 0.617021 (-5300 2575);
PAINT RED (-5300 2575);
FORCEPROP 1 LAST LOCATION C3P31
J 2
(-5300 2775);
DISPLAY 0.617021 (-5300 2775);
PAINT AQUA (-5300 2775);
FORCEPROP 1 LAST VALUE 0.22UF
J 2
(-5300 2725);
DISPLAY 0.617021 (-5300 2725);
PAINT SKYBLUE (-5300 2725);
FORCEPROP 1 LAST TOLERANCE 10%
J 2
(-5300 2625);
DISPLAY 0.617021 (-5300 2625);
PAINT SKYBLUE (-5300 2625);
FORCEPROP 1 LAST VOLTAGE 16V
J 2
(-5300 2675);
DISPLAY 0.617021 (-5300 2675);
PAINT SKYBLUE (-5300 2675);
FORCEPROP 1 LASTPIN (-5250 2575) $PN 2
J 2
(-5260 2555);
DISPLAY 0.787234 (-5260 2555);
PAINT ORANGE (-5260 2555);
DISPLAY INVISIBLE (-5260 2555);
FORCEPROP 2 LAST CDS_LIB mstr_discrete
J 0
(-5250 2675);
PAINT ORANGE (-5250 2675);
DISPLAY INVISIBLE (-5250 2675);
FORCEPROP 1 LASTPIN (-5250 2775) $PN 1
J 2
(-5260 2755);
DISPLAY 0.787234 (-5260 2755);
PAINT ORANGE (-5260 2755);
DISPLAY INVISIBLE (-5260 2755);
FORCEPROP 2 LAST CDS_LOCATION C3P31
J 2
(-5300 2775);
DISPLAY 0.617021 (-5300 2775);
PAINT AQUA (-5300 2775);
DISPLAY INVISIBLE (-5300 2775);
FORCEPROP 2 LAST CDS_SEC 1
J 0
(-5300 2875);
DISPLAY 1.021277 (-5300 2875);
PAINT ORANGE (-5300 2875);
DISPLAY INVISIBLE (-5300 2875);
FORCEPROP 2 LAST $SEC 1
J 0
(-5300 2875);
DISPLAY 0.680851 (-5300 2875);
PAINT MONO (-5300 2875);
DISPLAY INVISIBLE (-5300 2875);
FORCEPROP 1 LAST PATH I452
J 2
(-5300 2825);
DISPLAY 0.978723 (-5300 2825);
PAINT WHITE (-5300 2825);
DISPLAY INVISIBLE (-5300 2825);
FORCEADD TAP..7
(-5250 2425);
FORCEPROP 3 LASTPIN (-5250 2475) SIG_NAME P3E_CPU0_PE1_SS_C_TXP<5>
J 0
(-5240 2485);
DISPLAY 0.659574 (-5240 2485);
PAINT MONO (-5240 2485);
DISPLAY INVISIBLE (-5240 2485);
FORCEPROP 1 LASTPIN (-5250 2475) BN 5
R 1
J 0
(-5257 2423);
DISPLAY 0.617021 (-5257 2423);
PAINT GREEN (-5257 2423);
FORCEPROP 2 LAST CDS_LIB mstr_standard
J 0
(-5250 2425);
PAINT ORANGE (-5250 2425);
DISPLAY INVISIBLE (-5250 2425);
FORCEPROP 1 LAST BODY_TYPE PLUMBING
J 0
(-5200 2425);
DISPLAY 2.276596 (-5200 2425);
PAINT GREEN (-5200 2425);
DISPLAY INVISIBLE (-5200 2425);
FORCEPROP 1 LAST PATH I453
J 0
(-5252 2425);
DISPLAY 0.872340 (-5252 2425);
PAINT GREEN (-5252 2425);
DISPLAY INVISIBLE (-5252 2425);
FORCEPROP 1 LAST HDL_TAP TRUE
J 0
(-4930 2295);
DISPLAY 2.276596 (-4930 2295);
PAINT GREEN (-4930 2295);
DISPLAY INVISIBLE (-4930 2295);
FORCEADD TAP..7
(-5650 2425);
FORCEPROP 3 LASTPIN (-5650 2475) SIG_NAME P3E_CPU0_PE1_SS_C_TXP<7>
J 0
(-5640 2485);
DISPLAY 0.659574 (-5640 2485);
PAINT MONO (-5640 2485);
DISPLAY INVISIBLE (-5640 2485);
FORCEPROP 1 LASTPIN (-5650 2475) BN 7
R 1
J 0
(-5657 2423);
DISPLAY 0.617021 (-5657 2423);
PAINT GREEN (-5657 2423);
FORCEPROP 1 LAST PATH I454
J 0
(-5652 2425);
DISPLAY 0.872340 (-5652 2425);
PAINT GREEN (-5652 2425);
DISPLAY INVISIBLE (-5652 2425);
FORCEPROP 2 LAST CDS_LIB mstr_standard
J 0
(-5650 2425);
PAINT ORANGE (-5650 2425);
DISPLAY INVISIBLE (-5650 2425);
FORCEPROP 1 LAST BODY_TYPE PLUMBING
J 0
(-5600 2425);
DISPLAY 2.276596 (-5600 2425);
PAINT GREEN (-5600 2425);
DISPLAY INVISIBLE (-5600 2425);
FORCEPROP 1 LAST HDL_TAP TRUE
J 0
(-5330 2295);
DISPLAY 2.276596 (-5330 2295);
PAINT GREEN (-5330 2295);
DISPLAY INVISIBLE (-5330 2295);
FORCEADD CAP..1
R 2
(-5650 2675);
FORCEPROP 1 LAST PART_NUMBER A36096-155
J 2
(-5700 2525);
DISPLAY 0.617021 (-5700 2525);
PAINT BLUE (-5700 2525);
FORCEPROP 1 LAST PACK_TYPE 0402
J 2
(-5700 2475);
DISPLAY 0.617021 (-5700 2475);
PAINT SKYBLUE (-5700 2475);
FORCEPROP 1 LAST MATERIAL EMPTY
J 2
(-5700 2575);
DISPLAY 0.617021 (-5700 2575);
PAINT RED (-5700 2575);
FORCEPROP 1 LAST LOCATION C3P38
J 2
(-5700 2775);
DISPLAY 0.617021 (-5700 2775);
PAINT AQUA (-5700 2775);
FORCEPROP 1 LAST VALUE 0.22UF
J 2
(-5700 2725);
DISPLAY 0.617021 (-5700 2725);
PAINT SKYBLUE (-5700 2725);
FORCEPROP 1 LAST TOLERANCE 10%
J 2
(-5700 2625);
DISPLAY 0.617021 (-5700 2625);
PAINT SKYBLUE (-5700 2625);
FORCEPROP 1 LAST VOLTAGE 16V
J 2
(-5700 2675);
DISPLAY 0.617021 (-5700 2675);
PAINT SKYBLUE (-5700 2675);
FORCEPROP 1 LASTPIN (-5650 2575) $PN 2
J 2
(-5660 2555);
DISPLAY 0.787234 (-5660 2555);
PAINT ORANGE (-5660 2555);
DISPLAY INVISIBLE (-5660 2555);
FORCEPROP 2 LAST CDS_LIB mstr_discrete
J 0
(-5650 2675);
PAINT ORANGE (-5650 2675);
DISPLAY INVISIBLE (-5650 2675);
FORCEPROP 2 LAST CDS_LOCATION C3P38
J 2
(-5700 2775);
DISPLAY 0.617021 (-5700 2775);
PAINT AQUA (-5700 2775);
DISPLAY INVISIBLE (-5700 2775);
FORCEPROP 1 LASTPIN (-5650 2775) $PN 1
J 2
(-5660 2755);
DISPLAY 0.787234 (-5660 2755);
PAINT ORANGE (-5660 2755);
DISPLAY INVISIBLE (-5660 2755);
FORCEPROP 2 LAST CDS_SEC 1
J 0
(-5700 2875);
DISPLAY 1.021277 (-5700 2875);
PAINT ORANGE (-5700 2875);
DISPLAY INVISIBLE (-5700 2875);
FORCEPROP 2 LAST $SEC 1
J 0
(-5700 2875);
DISPLAY 0.680851 (-5700 2875);
PAINT MONO (-5700 2875);
DISPLAY INVISIBLE (-5700 2875);
FORCEPROP 1 LAST PATH I455
J 2
(-5700 2825);
DISPLAY 0.978723 (-5700 2825);
PAINT WHITE (-5700 2825);
DISPLAY INVISIBLE (-5700 2825);
FORCEADD OFFPAGE..1
(-6000 4275);
FORCEPROP 2 LAST $XR0 30 
J 0
(-6221 4275);
DISPLAY 0.638298 (-6221 4275);
PAINT MONO (-6221 4275);
FORCEPROP 2 LAST $XR1 107 
J 0
(-6341 4275);
DISPLAY 0.638298 (-6341 4275);
PAINT MONO (-6341 4275);
FORCEPROP 2 LAST PATH I456
J 0
(-5950 4350);
DISPLAY 1.021277 (-5950 4350);
PAINT ORANGE (-5950 4350);
DISPLAY INVISIBLE (-5950 4350);
FORCEPROP 2 LAST CDS_LIB mstr_standard
J 0
(-6000 4275);
PAINT ORANGE (-6000 4275);
DISPLAY INVISIBLE (-6000 4275);
FORCEPROP 1 LAST COMMENT_BODY TRUE
J 0
(-5875 4175);
DISPLAY 0.872340 (-5875 4175);
PAINT GREEN (-5875 4175);
DISPLAY INVISIBLE (-5875 4175);
FORCEPROP 1 LAST OFFPAGE TRUE
J 0
(-5675 4150);
DISPLAY 0.872340 (-5675 4150);
PAINT GREEN (-5675 4150);
DISPLAY INVISIBLE (-5675 4150);
FORCEADD OFFPAGE..1
(-5950 3275);
FORCEPROP 2 LAST $XR0 30 
J 0
(-6201 3275);
DISPLAY 0.638298 (-6201 3275);
PAINT MONO (-6201 3275);
FORCEPROP 2 LAST $XR1 107 
J 0
(-6321 3275);
DISPLAY 0.638298 (-6321 3275);
PAINT MONO (-6321 3275);
FORCEPROP 2 LAST CDS_LIB mstr_standard
J 0
(-5950 3275);
PAINT ORANGE (-5950 3275);
DISPLAY INVISIBLE (-5950 3275);
FORCEPROP 2 LAST PATH I457
J 0
(-5900 3350);
DISPLAY 1.021277 (-5900 3350);
PAINT ORANGE (-5900 3350);
DISPLAY INVISIBLE (-5900 3350);
FORCEPROP 1 LAST COMMENT_BODY TRUE
J 0
(-5825 3175);
DISPLAY 0.872340 (-5825 3175);
PAINT GREEN (-5825 3175);
DISPLAY INVISIBLE (-5825 3175);
FORCEPROP 1 LAST OFFPAGE TRUE
J 0
(-5625 3150);
DISPLAY 0.872340 (-5625 3150);
PAINT GREEN (-5625 3150);
DISPLAY INVISIBLE (-5625 3150);
FORCEADD RES..2
(-2225 3825);
FORCEPROP 1 LAST PACK_TYPE 0402
J 0
(-2185 3650);
DISPLAY 0.617021 (-2185 3650);
PAINT SKYBLUE (-2185 3650);
FORCEPROP 1 LAST VALUE 0.0
J 0
(-2180 3900);
DISPLAY 0.617021 (-2180 3900);
PAINT SKYBLUE (-2180 3900);
FORCEPROP 1 LAST TOLERANCE 5%
J 0
(-2180 3850);
DISPLAY 0.617021 (-2180 3850);
PAINT SKYBLUE (-2180 3850);
FORCEPROP 1 LAST MATERIAL EMPTY
J 0
(-2185 3750);
DISPLAY 0.617021 (-2185 3750);
PAINT RED (-2185 3750);
FORCEPROP 1 LAST LOCATION R2U29
J 0
(-2180 3950);
DISPLAY 0.617021 (-2180 3950);
PAINT AQUA (-2180 3950);
FORCEPROP 1 LAST PART_NUMBER G21497-005
J 0
(-2185 3700);
DISPLAY 0.617021 (-2185 3700);
PAINT BLUE (-2185 3700);
FORCEPROP 1 LAST WATTAGE 1/16W
J 0
(-2185 3800);
DISPLAY 0.617021 (-2185 3800);
PAINT SKYBLUE (-2185 3800);
FORCEPROP 1 LASTPIN (-2225 3725) $PN 2
J 0
(-2220 3735);
DISPLAY 0.787234 (-2220 3735);
PAINT ORANGE (-2220 3735);
DISPLAY INVISIBLE (-2220 3735);
FORCEPROP 2 LAST CDS_LIB mstr_discrete
J 0
(-2225 3825);
PAINT ORANGE (-2225 3825);
DISPLAY INVISIBLE (-2225 3825);
FORCEPROP 1 LASTPIN (-2225 3925) $PN 1
J 0
(-2220 3887);
DISPLAY 0.787234 (-2220 3887);
PAINT ORANGE (-2220 3887);
DISPLAY INVISIBLE (-2220 3887);
FORCEPROP 2 LAST CDS_LOCATION R2U29
J 0
(-2180 3950);
DISPLAY 0.617021 (-2180 3950);
PAINT AQUA (-2180 3950);
DISPLAY INVISIBLE (-2180 3950);
FORCEPROP 2 LAST CDS_SEC 1
J 0
(-2175 4050);
DISPLAY 1.021277 (-2175 4050);
PAINT ORANGE (-2175 4050);
DISPLAY INVISIBLE (-2175 4050);
FORCEPROP 2 LAST $SEC 1
J 0
(-2175 4050);
DISPLAY 0.680851 (-2175 4050);
PAINT MONO (-2175 4050);
DISPLAY INVISIBLE (-2175 4050);
FORCEPROP 1 LAST PATH I458
J 0
(-2175 4000);
DISPLAY 0.978723 (-2175 4000);
PAINT WHITE (-2175 4000);
DISPLAY INVISIBLE (-2175 4000);
FORCEADD RES..2
(-2025 4125);
FORCEPROP 1 LAST MATERIAL EMPTY
J 0
(-1985 4050);
DISPLAY 0.617021 (-1985 4050);
PAINT RED (-1985 4050);
FORCEPROP 1 LAST PACK_TYPE 0402
J 0
(-1985 3950);
DISPLAY 0.617021 (-1985 3950);
PAINT SKYBLUE (-1985 3950);
FORCEPROP 1 LAST PART_NUMBER G21497-005
J 0
(-1985 4000);
DISPLAY 0.617021 (-1985 4000);
PAINT BLUE (-1985 4000);
FORCEPROP 1 LAST TOLERANCE 5%
J 0
(-1980 4150);
DISPLAY 0.617021 (-1980 4150);
PAINT SKYBLUE (-1980 4150);
FORCEPROP 1 LAST LOCATION R2U27
J 0
(-1980 4250);
DISPLAY 0.617021 (-1980 4250);
PAINT AQUA (-1980 4250);
FORCEPROP 1 LAST VALUE 0.0
J 0
(-1980 4200);
DISPLAY 0.617021 (-1980 4200);
PAINT SKYBLUE (-1980 4200);
FORCEPROP 1 LAST WATTAGE 1/16W
J 0
(-1985 4100);
DISPLAY 0.617021 (-1985 4100);
PAINT SKYBLUE (-1985 4100);
FORCEPROP 1 LASTPIN (-2025 4025) $PN 2
J 0
(-2020 4035);
DISPLAY 0.787234 (-2020 4035);
PAINT ORANGE (-2020 4035);
DISPLAY INVISIBLE (-2020 4035);
FORCEPROP 1 LASTPIN (-2025 4225) $PN 1
J 0
(-2020 4187);
DISPLAY 0.787234 (-2020 4187);
PAINT ORANGE (-2020 4187);
DISPLAY INVISIBLE (-2020 4187);
FORCEPROP 2 LAST CDS_LIB mstr_discrete
J 0
(-2025 4125);
PAINT ORANGE (-2025 4125);
DISPLAY INVISIBLE (-2025 4125);
FORCEPROP 2 LAST CDS_LOCATION R2U27
J 0
(-1980 4250);
DISPLAY 0.617021 (-1980 4250);
PAINT AQUA (-1980 4250);
DISPLAY INVISIBLE (-1980 4250);
FORCEPROP 1 LAST PATH I459
J 0
(-1975 4300);
DISPLAY 0.978723 (-1975 4300);
PAINT WHITE (-1975 4300);
DISPLAY INVISIBLE (-1975 4300);
FORCEPROP 2 LAST CDS_SEC 1
J 0
(-1975 4350);
DISPLAY 1.021277 (-1975 4350);
PAINT ORANGE (-1975 4350);
DISPLAY INVISIBLE (-1975 4350);
FORCEPROP 2 LAST $SEC 1
J 0
(-1975 4350);
DISPLAY 0.680851 (-1975 4350);
PAINT MONO (-1975 4350);
DISPLAY INVISIBLE (-1975 4350);
FORCEADD RES..2
(-1825 3825);
FORCEPROP 1 LAST PACK_TYPE 0402
J 0
(-1785 3650);
DISPLAY 0.617021 (-1785 3650);
PAINT SKYBLUE (-1785 3650);
FORCEPROP 1 LAST WATTAGE 1/16W
J 0
(-1785 3800);
DISPLAY 0.617021 (-1785 3800);
PAINT SKYBLUE (-1785 3800);
FORCEPROP 1 LAST MATERIAL EMPTY
J 0
(-1785 3750);
DISPLAY 0.617021 (-1785 3750);
PAINT RED (-1785 3750);
FORCEPROP 1 LAST TOLERANCE 5%
J 0
(-1780 3850);
DISPLAY 0.617021 (-1780 3850);
PAINT SKYBLUE (-1780 3850);
FORCEPROP 1 LAST VALUE 0.0
J 0
(-1780 3900);
DISPLAY 0.617021 (-1780 3900);
PAINT SKYBLUE (-1780 3900);
FORCEPROP 1 LAST LOCATION R2U25
J 0
(-1780 3950);
DISPLAY 0.617021 (-1780 3950);
PAINT AQUA (-1780 3950);
FORCEPROP 1 LAST PART_NUMBER G21497-005
J 0
(-1785 3700);
DISPLAY 0.617021 (-1785 3700);
PAINT BLUE (-1785 3700);
FORCEPROP 1 LASTPIN (-1825 3725) $PN 2
J 0
(-1820 3735);
DISPLAY 0.787234 (-1820 3735);
PAINT ORANGE (-1820 3735);
DISPLAY INVISIBLE (-1820 3735);
FORCEPROP 2 LAST CDS_LIB mstr_discrete
J 0
(-1825 3825);
PAINT ORANGE (-1825 3825);
DISPLAY INVISIBLE (-1825 3825);
FORCEPROP 1 LASTPIN (-1825 3925) $PN 1
J 0
(-1820 3887);
DISPLAY 0.787234 (-1820 3887);
PAINT ORANGE (-1820 3887);
DISPLAY INVISIBLE (-1820 3887);
FORCEPROP 2 LAST CDS_LOCATION R2U25
J 0
(-1780 3950);
DISPLAY 0.617021 (-1780 3950);
PAINT AQUA (-1780 3950);
DISPLAY INVISIBLE (-1780 3950);
FORCEPROP 2 LAST $SEC 1
J 0
(-1775 4050);
DISPLAY 0.680851 (-1775 4050);
PAINT MONO (-1775 4050);
DISPLAY INVISIBLE (-1775 4050);
FORCEPROP 2 LAST CDS_SEC 1
J 0
(-1775 4050);
DISPLAY 1.021277 (-1775 4050);
PAINT ORANGE (-1775 4050);
DISPLAY INVISIBLE (-1775 4050);
FORCEPROP 1 LAST PATH I460
J 0
(-1775 4000);
DISPLAY 0.978723 (-1775 4000);
PAINT WHITE (-1775 4000);
DISPLAY INVISIBLE (-1775 4000);
FORCEADD RES..2
(-1625 4125);
FORCEPROP 1 LAST MATERIAL EMPTY
J 0
(-1585 4050);
DISPLAY 0.617021 (-1585 4050);
PAINT RED (-1585 4050);
FORCEPROP 1 LAST PART_NUMBER G21497-005
J 0
(-1585 4000);
DISPLAY 0.617021 (-1585 4000);
PAINT BLUE (-1585 4000);
FORCEPROP 1 LAST PACK_TYPE 0402
J 0
(-1585 3950);
DISPLAY 0.617021 (-1585 3950);
PAINT SKYBLUE (-1585 3950);
FORCEPROP 1 LAST LOCATION R2U23
J 0
(-1580 4250);
DISPLAY 0.617021 (-1580 4250);
PAINT AQUA (-1580 4250);
FORCEPROP 1 LAST VALUE 0.0
J 0
(-1580 4200);
DISPLAY 0.617021 (-1580 4200);
PAINT SKYBLUE (-1580 4200);
FORCEPROP 1 LAST TOLERANCE 5%
J 0
(-1580 4150);
DISPLAY 0.617021 (-1580 4150);
PAINT SKYBLUE (-1580 4150);
FORCEPROP 1 LAST WATTAGE 1/16W
J 0
(-1585 4100);
DISPLAY 0.617021 (-1585 4100);
PAINT SKYBLUE (-1585 4100);
FORCEPROP 1 LASTPIN (-1625 4025) $PN 2
J 0
(-1620 4035);
DISPLAY 0.787234 (-1620 4035);
PAINT ORANGE (-1620 4035);
DISPLAY INVISIBLE (-1620 4035);
FORCEPROP 1 LASTPIN (-1625 4225) $PN 1
J 0
(-1620 4187);
DISPLAY 0.787234 (-1620 4187);
PAINT ORANGE (-1620 4187);
DISPLAY INVISIBLE (-1620 4187);
FORCEPROP 2 LAST CDS_LIB mstr_discrete
J 0
(-1625 4125);
PAINT ORANGE (-1625 4125);
DISPLAY INVISIBLE (-1625 4125);
FORCEPROP 2 LAST CDS_LOCATION R2U23
J 0
(-1580 4250);
DISPLAY 0.617021 (-1580 4250);
PAINT AQUA (-1580 4250);
DISPLAY INVISIBLE (-1580 4250);
FORCEPROP 1 LAST PATH I461
J 0
(-1575 4300);
DISPLAY 0.978723 (-1575 4300);
PAINT WHITE (-1575 4300);
DISPLAY INVISIBLE (-1575 4300);
FORCEPROP 2 LAST CDS_SEC 1
J 0
(-1575 4350);
DISPLAY 1.021277 (-1575 4350);
PAINT ORANGE (-1575 4350);
DISPLAY INVISIBLE (-1575 4350);
FORCEPROP 2 LAST $SEC 1
J 0
(-1575 4350);
DISPLAY 0.680851 (-1575 4350);
PAINT MONO (-1575 4350);
DISPLAY INVISIBLE (-1575 4350);
FORCEADD RES..2
(-1425 3825);
FORCEPROP 1 LAST TOLERANCE 5%
J 0
(-1380 3850);
DISPLAY 0.617021 (-1380 3850);
PAINT SKYBLUE (-1380 3850);
FORCEPROP 1 LAST VALUE 0.0
J 0
(-1380 3900);
DISPLAY 0.617021 (-1380 3900);
PAINT SKYBLUE (-1380 3900);
FORCEPROP 1 LAST MATERIAL EMPTY
J 0
(-1385 3750);
DISPLAY 0.617021 (-1385 3750);
PAINT RED (-1385 3750);
FORCEPROP 1 LAST LOCATION R2U21
J 0
(-1380 3950);
DISPLAY 0.617021 (-1380 3950);
PAINT AQUA (-1380 3950);
FORCEPROP 1 LAST PART_NUMBER G21497-005
J 0
(-1385 3700);
DISPLAY 0.617021 (-1385 3700);
PAINT BLUE (-1385 3700);
FORCEPROP 1 LAST PACK_TYPE 0402
J 0
(-1385 3650);
DISPLAY 0.617021 (-1385 3650);
PAINT SKYBLUE (-1385 3650);
FORCEPROP 1 LAST WATTAGE 1/16W
J 0
(-1385 3800);
DISPLAY 0.617021 (-1385 3800);
PAINT SKYBLUE (-1385 3800);
FORCEPROP 1 LASTPIN (-1425 3725) $PN 2
J 0
(-1420 3735);
DISPLAY 0.787234 (-1420 3735);
PAINT ORANGE (-1420 3735);
DISPLAY INVISIBLE (-1420 3735);
FORCEPROP 2 LAST CDS_LIB mstr_discrete
J 0
(-1425 3825);
PAINT ORANGE (-1425 3825);
DISPLAY INVISIBLE (-1425 3825);
FORCEPROP 1 LASTPIN (-1425 3925) $PN 1
J 0
(-1420 3887);
DISPLAY 0.787234 (-1420 3887);
PAINT ORANGE (-1420 3887);
DISPLAY INVISIBLE (-1420 3887);
FORCEPROP 2 LAST CDS_LOCATION R2U21
J 0
(-1380 3950);
DISPLAY 0.617021 (-1380 3950);
PAINT AQUA (-1380 3950);
DISPLAY INVISIBLE (-1380 3950);
FORCEPROP 2 LAST $SEC 1
J 0
(-1375 4050);
DISPLAY 0.680851 (-1375 4050);
PAINT MONO (-1375 4050);
DISPLAY INVISIBLE (-1375 4050);
FORCEPROP 2 LAST CDS_SEC 1
J 0
(-1375 4050);
DISPLAY 1.021277 (-1375 4050);
PAINT ORANGE (-1375 4050);
DISPLAY INVISIBLE (-1375 4050);
FORCEPROP 1 LAST PATH I462
J 0
(-1375 4000);
DISPLAY 0.978723 (-1375 4000);
PAINT WHITE (-1375 4000);
DISPLAY INVISIBLE (-1375 4000);
FORCEADD RES..2
(-1225 4125);
FORCEPROP 1 LAST MATERIAL EMPTY
J 0
(-1185 4050);
DISPLAY 0.617021 (-1185 4050);
PAINT RED (-1185 4050);
FORCEPROP 1 LAST PACK_TYPE 0402
J 0
(-1185 3950);
DISPLAY 0.617021 (-1185 3950);
PAINT SKYBLUE (-1185 3950);
FORCEPROP 1 LAST PART_NUMBER G21497-005
J 0
(-1185 4000);
DISPLAY 0.617021 (-1185 4000);
PAINT BLUE (-1185 4000);
FORCEPROP 1 LAST LOCATION R2U19
J 0
(-1180 4250);
DISPLAY 0.617021 (-1180 4250);
PAINT AQUA (-1180 4250);
FORCEPROP 1 LAST VALUE 0.0
J 0
(-1180 4200);
DISPLAY 0.617021 (-1180 4200);
PAINT SKYBLUE (-1180 4200);
FORCEPROP 1 LAST TOLERANCE 5%
J 0
(-1180 4150);
DISPLAY 0.617021 (-1180 4150);
PAINT SKYBLUE (-1180 4150);
FORCEPROP 1 LAST WATTAGE 1/16W
J 0
(-1185 4100);
DISPLAY 0.617021 (-1185 4100);
PAINT SKYBLUE (-1185 4100);
FORCEPROP 1 LASTPIN (-1225 4025) $PN 2
J 0
(-1220 4035);
DISPLAY 0.787234 (-1220 4035);
PAINT ORANGE (-1220 4035);
DISPLAY INVISIBLE (-1220 4035);
FORCEPROP 1 LASTPIN (-1225 4225) $PN 1
J 0
(-1220 4187);
DISPLAY 0.787234 (-1220 4187);
PAINT ORANGE (-1220 4187);
DISPLAY INVISIBLE (-1220 4187);
FORCEPROP 2 LAST CDS_LIB mstr_discrete
J 0
(-1225 4125);
PAINT ORANGE (-1225 4125);
DISPLAY INVISIBLE (-1225 4125);
FORCEPROP 2 LAST CDS_LOCATION R2U19
J 0
(-1180 4250);
DISPLAY 0.617021 (-1180 4250);
PAINT AQUA (-1180 4250);
DISPLAY INVISIBLE (-1180 4250);
FORCEPROP 1 LAST PATH I463
J 0
(-1175 4300);
DISPLAY 0.978723 (-1175 4300);
PAINT WHITE (-1175 4300);
DISPLAY INVISIBLE (-1175 4300);
FORCEPROP 2 LAST CDS_SEC 1
J 0
(-1175 4350);
DISPLAY 1.021277 (-1175 4350);
PAINT ORANGE (-1175 4350);
DISPLAY INVISIBLE (-1175 4350);
FORCEPROP 2 LAST $SEC 1
J 0
(-1175 4350);
DISPLAY 0.680851 (-1175 4350);
PAINT MONO (-1175 4350);
DISPLAY INVISIBLE (-1175 4350);
FORCEADD RES..2
(-1025 3825);
FORCEPROP 1 LAST MATERIAL EMPTY
J 0
(-985 3750);
DISPLAY 0.617021 (-985 3750);
PAINT RED (-985 3750);
FORCEPROP 1 LAST PACK_TYPE 0402
J 0
(-985 3650);
DISPLAY 0.617021 (-985 3650);
PAINT SKYBLUE (-985 3650);
FORCEPROP 1 LAST WATTAGE 1/16W
J 0
(-985 3800);
DISPLAY 0.617021 (-985 3800);
PAINT SKYBLUE (-985 3800);
FORCEPROP 1 LAST TOLERANCE 5%
J 0
(-980 3850);
DISPLAY 0.617021 (-980 3850);
PAINT SKYBLUE (-980 3850);
FORCEPROP 1 LAST LOCATION R2U17
J 0
(-980 3950);
DISPLAY 0.617021 (-980 3950);
PAINT AQUA (-980 3950);
FORCEPROP 1 LAST VALUE 0.0
J 0
(-980 3900);
DISPLAY 0.617021 (-980 3900);
PAINT SKYBLUE (-980 3900);
FORCEPROP 1 LAST PART_NUMBER G21497-005
J 0
(-985 3700);
DISPLAY 0.617021 (-985 3700);
PAINT BLUE (-985 3700);
FORCEPROP 2 LAST CDS_LIB mstr_discrete
J 0
(-1025 3825);
PAINT ORANGE (-1025 3825);
DISPLAY INVISIBLE (-1025 3825);
FORCEPROP 1 LASTPIN (-1025 3725) $PN 2
J 0
(-1020 3735);
DISPLAY 0.787234 (-1020 3735);
PAINT ORANGE (-1020 3735);
DISPLAY INVISIBLE (-1020 3735);
FORCEPROP 1 LASTPIN (-1025 3925) $PN 1
J 0
(-1020 3887);
DISPLAY 0.787234 (-1020 3887);
PAINT ORANGE (-1020 3887);
DISPLAY INVISIBLE (-1020 3887);
FORCEPROP 2 LAST CDS_LOCATION R2U17
J 0
(-980 3950);
DISPLAY 0.617021 (-980 3950);
PAINT AQUA (-980 3950);
DISPLAY INVISIBLE (-980 3950);
FORCEPROP 1 LAST PATH I464
J 0
(-975 4000);
DISPLAY 0.978723 (-975 4000);
PAINT WHITE (-975 4000);
DISPLAY INVISIBLE (-975 4000);
FORCEPROP 2 LAST $SEC 1
J 0
(-975 4050);
DISPLAY 0.680851 (-975 4050);
PAINT MONO (-975 4050);
DISPLAY INVISIBLE (-975 4050);
FORCEPROP 2 LAST CDS_SEC 1
J 0
(-975 4050);
DISPLAY 1.021277 (-975 4050);
PAINT ORANGE (-975 4050);
DISPLAY INVISIBLE (-975 4050);
FORCEADD RES..2
(-825 4125);
FORCEPROP 1 LAST MATERIAL EMPTY
J 0
(-785 4050);
DISPLAY 0.617021 (-785 4050);
PAINT RED (-785 4050);
FORCEPROP 1 LAST PACK_TYPE 0402
J 0
(-785 3950);
DISPLAY 0.617021 (-785 3950);
PAINT SKYBLUE (-785 3950);
FORCEPROP 1 LAST PART_NUMBER G21497-005
J 0
(-785 4000);
DISPLAY 0.617021 (-785 4000);
PAINT BLUE (-785 4000);
FORCEPROP 1 LAST LOCATION R2U15
J 0
(-780 4250);
DISPLAY 0.617021 (-780 4250);
PAINT AQUA (-780 4250);
FORCEPROP 1 LAST VALUE 0.0
J 0
(-780 4200);
DISPLAY 0.617021 (-780 4200);
PAINT SKYBLUE (-780 4200);
FORCEPROP 1 LAST TOLERANCE 5%
J 0
(-780 4150);
DISPLAY 0.617021 (-780 4150);
PAINT SKYBLUE (-780 4150);
FORCEPROP 1 LAST WATTAGE 1/16W
J 0
(-785 4100);
DISPLAY 0.617021 (-785 4100);
PAINT SKYBLUE (-785 4100);
FORCEPROP 1 LASTPIN (-825 4025) $PN 2
J 0
(-820 4035);
DISPLAY 0.787234 (-820 4035);
PAINT ORANGE (-820 4035);
DISPLAY INVISIBLE (-820 4035);
FORCEPROP 1 LASTPIN (-825 4225) $PN 1
J 0
(-820 4187);
DISPLAY 0.787234 (-820 4187);
PAINT ORANGE (-820 4187);
DISPLAY INVISIBLE (-820 4187);
FORCEPROP 2 LAST CDS_LIB mstr_discrete
J 0
(-825 4125);
PAINT ORANGE (-825 4125);
DISPLAY INVISIBLE (-825 4125);
FORCEPROP 2 LAST CDS_LOCATION R2U15
J 0
(-780 4250);
DISPLAY 0.617021 (-780 4250);
PAINT AQUA (-780 4250);
DISPLAY INVISIBLE (-780 4250);
FORCEPROP 1 LAST PATH I465
J 0
(-775 4300);
DISPLAY 0.978723 (-775 4300);
PAINT WHITE (-775 4300);
DISPLAY INVISIBLE (-775 4300);
FORCEPROP 2 LAST CDS_SEC 1
J 0
(-775 4350);
DISPLAY 1.021277 (-775 4350);
PAINT ORANGE (-775 4350);
DISPLAY INVISIBLE (-775 4350);
FORCEPROP 2 LAST $SEC 1
J 0
(-775 4350);
DISPLAY 0.680851 (-775 4350);
PAINT MONO (-775 4350);
DISPLAY INVISIBLE (-775 4350);
FORCEADD RES..2
(-800 3100);
FORCEPROP 1 LAST MATERIAL EMPTY
J 0
(-760 3025);
DISPLAY 0.617021 (-760 3025);
PAINT RED (-760 3025);
FORCEPROP 1 LAST PACK_TYPE 0402
J 0
(-760 2925);
DISPLAY 0.617021 (-760 2925);
PAINT SKYBLUE (-760 2925);
FORCEPROP 1 LAST PART_NUMBER G21497-005
J 0
(-760 2975);
DISPLAY 0.617021 (-760 2975);
PAINT BLUE (-760 2975);
FORCEPROP 1 LAST TOLERANCE 5%
J 0
(-755 3125);
DISPLAY 0.617021 (-755 3125);
PAINT SKYBLUE (-755 3125);
FORCEPROP 1 LAST VALUE 0.0
J 0
(-755 3175);
DISPLAY 0.617021 (-755 3175);
PAINT SKYBLUE (-755 3175);
FORCEPROP 1 LAST WATTAGE 1/16W
J 0
(-760 3075);
DISPLAY 0.617021 (-760 3075);
PAINT SKYBLUE (-760 3075);
FORCEPROP 1 LAST LOCATION R2U14
J 0
(-755 3225);
DISPLAY 0.617021 (-755 3225);
PAINT AQUA (-755 3225);
FORCEPROP 1 LASTPIN (-800 3000) $PN 2
J 0
(-795 3010);
DISPLAY 0.787234 (-795 3010);
PAINT ORANGE (-795 3010);
DISPLAY INVISIBLE (-795 3010);
FORCEPROP 1 LASTPIN (-800 3200) $PN 1
J 0
(-795 3162);
DISPLAY 0.787234 (-795 3162);
PAINT ORANGE (-795 3162);
DISPLAY INVISIBLE (-795 3162);
FORCEPROP 2 LAST CDS_LIB mstr_discrete
J 0
(-800 3100);
PAINT ORANGE (-800 3100);
DISPLAY INVISIBLE (-800 3100);
FORCEPROP 2 LAST CDS_LOCATION R2U14
J 0
(-755 3225);
DISPLAY 0.617021 (-755 3225);
PAINT AQUA (-755 3225);
DISPLAY INVISIBLE (-755 3225);
FORCEPROP 1 LAST PATH I466
J 0
(-750 3275);
DISPLAY 0.978723 (-750 3275);
PAINT WHITE (-750 3275);
DISPLAY INVISIBLE (-750 3275);
FORCEPROP 2 LAST CDS_SEC 1
J 0
(-750 3325);
DISPLAY 1.021277 (-750 3325);
PAINT ORANGE (-750 3325);
DISPLAY INVISIBLE (-750 3325);
FORCEPROP 2 LAST $SEC 1
J 0
(-750 3325);
DISPLAY 0.680851 (-750 3325);
PAINT MONO (-750 3325);
DISPLAY INVISIBLE (-750 3325);
FORCEADD RES..2
(-1000 2800);
FORCEPROP 1 LAST MATERIAL EMPTY
J 0
(-960 2725);
DISPLAY 0.617021 (-960 2725);
PAINT RED (-960 2725);
FORCEPROP 1 LAST PACK_TYPE 0402
J 0
(-960 2625);
DISPLAY 0.617021 (-960 2625);
PAINT SKYBLUE (-960 2625);
FORCEPROP 1 LAST WATTAGE 1/16W
J 0
(-960 2775);
DISPLAY 0.617021 (-960 2775);
PAINT SKYBLUE (-960 2775);
FORCEPROP 1 LAST TOLERANCE 5%
J 0
(-955 2825);
DISPLAY 0.617021 (-955 2825);
PAINT SKYBLUE (-955 2825);
FORCEPROP 1 LAST LOCATION R2U16
J 0
(-955 2925);
DISPLAY 0.617021 (-955 2925);
PAINT AQUA (-955 2925);
FORCEPROP 1 LAST VALUE 0.0
J 0
(-955 2875);
DISPLAY 0.617021 (-955 2875);
PAINT SKYBLUE (-955 2875);
FORCEPROP 1 LAST PART_NUMBER G21497-005
J 0
(-960 2675);
DISPLAY 0.617021 (-960 2675);
PAINT BLUE (-960 2675);
FORCEPROP 1 LASTPIN (-1000 2700) $PN 2
J 0
(-995 2710);
DISPLAY 0.787234 (-995 2710);
PAINT ORANGE (-995 2710);
DISPLAY INVISIBLE (-995 2710);
FORCEPROP 2 LAST CDS_LIB mstr_discrete
J 0
(-1000 2800);
PAINT ORANGE (-1000 2800);
DISPLAY INVISIBLE (-1000 2800);
FORCEPROP 1 LASTPIN (-1000 2900) $PN 1
J 0
(-995 2862);
DISPLAY 0.787234 (-995 2862);
PAINT ORANGE (-995 2862);
DISPLAY INVISIBLE (-995 2862);
FORCEPROP 2 LAST CDS_LOCATION R2U16
J 0
(-955 2925);
DISPLAY 0.617021 (-955 2925);
PAINT AQUA (-955 2925);
DISPLAY INVISIBLE (-955 2925);
FORCEPROP 2 LAST CDS_SEC 1
J 0
(-950 3025);
DISPLAY 1.021277 (-950 3025);
PAINT ORANGE (-950 3025);
DISPLAY INVISIBLE (-950 3025);
FORCEPROP 2 LAST $SEC 1
J 0
(-950 3025);
DISPLAY 0.680851 (-950 3025);
PAINT MONO (-950 3025);
DISPLAY INVISIBLE (-950 3025);
FORCEPROP 1 LAST PATH I467
J 0
(-950 2975);
DISPLAY 0.978723 (-950 2975);
PAINT WHITE (-950 2975);
DISPLAY INVISIBLE (-950 2975);
FORCEADD RES..2
(-1200 3100);
FORCEPROP 1 LAST PACK_TYPE 0402
J 0
(-1160 2925);
DISPLAY 0.617021 (-1160 2925);
PAINT SKYBLUE (-1160 2925);
FORCEPROP 1 LAST VALUE 0.0
J 0
(-1155 3175);
DISPLAY 0.617021 (-1155 3175);
PAINT SKYBLUE (-1155 3175);
FORCEPROP 1 LAST TOLERANCE 5%
J 0
(-1155 3125);
DISPLAY 0.617021 (-1155 3125);
PAINT SKYBLUE (-1155 3125);
FORCEPROP 1 LAST MATERIAL EMPTY
J 0
(-1160 3025);
DISPLAY 0.617021 (-1160 3025);
PAINT RED (-1160 3025);
FORCEPROP 1 LAST LOCATION R2U18
J 0
(-1155 3225);
DISPLAY 0.617021 (-1155 3225);
PAINT AQUA (-1155 3225);
FORCEPROP 1 LAST PART_NUMBER G21497-005
J 0
(-1160 2975);
DISPLAY 0.617021 (-1160 2975);
PAINT BLUE (-1160 2975);
FORCEPROP 1 LAST WATTAGE 1/16W
J 0
(-1160 3075);
DISPLAY 0.617021 (-1160 3075);
PAINT SKYBLUE (-1160 3075);
FORCEPROP 1 LASTPIN (-1200 3000) $PN 2
J 0
(-1195 3010);
DISPLAY 0.787234 (-1195 3010);
PAINT ORANGE (-1195 3010);
DISPLAY INVISIBLE (-1195 3010);
FORCEPROP 1 LASTPIN (-1200 3200) $PN 1
J 0
(-1195 3162);
DISPLAY 0.787234 (-1195 3162);
PAINT ORANGE (-1195 3162);
DISPLAY INVISIBLE (-1195 3162);
FORCEPROP 2 LAST CDS_LIB mstr_discrete
J 0
(-1200 3100);
PAINT ORANGE (-1200 3100);
DISPLAY INVISIBLE (-1200 3100);
FORCEPROP 2 LAST CDS_LOCATION R2U18
J 0
(-1155 3225);
DISPLAY 0.617021 (-1155 3225);
PAINT AQUA (-1155 3225);
DISPLAY INVISIBLE (-1155 3225);
FORCEPROP 1 LAST PATH I468
J 0
(-1150 3275);
DISPLAY 0.978723 (-1150 3275);
PAINT WHITE (-1150 3275);
DISPLAY INVISIBLE (-1150 3275);
FORCEPROP 2 LAST CDS_SEC 1
J 0
(-1150 3325);
DISPLAY 1.021277 (-1150 3325);
PAINT ORANGE (-1150 3325);
DISPLAY INVISIBLE (-1150 3325);
FORCEPROP 2 LAST $SEC 1
J 0
(-1150 3325);
DISPLAY 0.680851 (-1150 3325);
PAINT MONO (-1150 3325);
DISPLAY INVISIBLE (-1150 3325);
FORCEADD RES..2
(-1400 2800);
FORCEPROP 1 LAST TOLERANCE 5%
J 0
(-1355 2825);
DISPLAY 0.617021 (-1355 2825);
PAINT SKYBLUE (-1355 2825);
FORCEPROP 1 LAST MATERIAL EMPTY
J 0
(-1360 2725);
DISPLAY 0.617021 (-1360 2725);
PAINT RED (-1360 2725);
FORCEPROP 1 LAST LOCATION R2U20
J 0
(-1355 2925);
DISPLAY 0.617021 (-1355 2925);
PAINT AQUA (-1355 2925);
FORCEPROP 1 LAST PART_NUMBER G21497-005
J 0
(-1360 2675);
DISPLAY 0.617021 (-1360 2675);
PAINT BLUE (-1360 2675);
FORCEPROP 1 LAST VALUE 0.0
J 0
(-1355 2875);
DISPLAY 0.617021 (-1355 2875);
PAINT SKYBLUE (-1355 2875);
FORCEPROP 1 LAST PACK_TYPE 0402
J 0
(-1360 2625);
DISPLAY 0.617021 (-1360 2625);
PAINT SKYBLUE (-1360 2625);
FORCEPROP 1 LAST WATTAGE 1/16W
J 0
(-1360 2775);
DISPLAY 0.617021 (-1360 2775);
PAINT SKYBLUE (-1360 2775);
FORCEPROP 1 LASTPIN (-1400 2700) $PN 2
J 0
(-1395 2710);
DISPLAY 0.787234 (-1395 2710);
PAINT ORANGE (-1395 2710);
DISPLAY INVISIBLE (-1395 2710);
FORCEPROP 2 LAST CDS_LIB mstr_discrete
J 0
(-1400 2800);
PAINT ORANGE (-1400 2800);
DISPLAY INVISIBLE (-1400 2800);
FORCEPROP 1 LASTPIN (-1400 2900) $PN 1
J 0
(-1395 2862);
DISPLAY 0.787234 (-1395 2862);
PAINT ORANGE (-1395 2862);
DISPLAY INVISIBLE (-1395 2862);
FORCEPROP 2 LAST CDS_LOCATION R2U20
J 0
(-1355 2925);
DISPLAY 0.617021 (-1355 2925);
PAINT AQUA (-1355 2925);
DISPLAY INVISIBLE (-1355 2925);
FORCEPROP 2 LAST $SEC 1
J 0
(-1350 3025);
DISPLAY 0.680851 (-1350 3025);
PAINT MONO (-1350 3025);
DISPLAY INVISIBLE (-1350 3025);
FORCEPROP 2 LAST CDS_SEC 1
J 0
(-1350 3025);
DISPLAY 1.021277 (-1350 3025);
PAINT ORANGE (-1350 3025);
DISPLAY INVISIBLE (-1350 3025);
FORCEPROP 1 LAST PATH I469
J 0
(-1350 2975);
DISPLAY 0.978723 (-1350 2975);
PAINT WHITE (-1350 2975);
DISPLAY INVISIBLE (-1350 2975);
FORCEADD RES..2
(-1600 3100);
FORCEPROP 1 LAST MATERIAL EMPTY
J 0
(-1560 3025);
DISPLAY 0.617021 (-1560 3025);
PAINT RED (-1560 3025);
FORCEPROP 1 LAST PART_NUMBER G21497-005
J 0
(-1560 2975);
DISPLAY 0.617021 (-1560 2975);
PAINT BLUE (-1560 2975);
FORCEPROP 1 LAST PACK_TYPE 0402
J 0
(-1560 2925);
DISPLAY 0.617021 (-1560 2925);
PAINT SKYBLUE (-1560 2925);
FORCEPROP 1 LAST LOCATION R2U22
J 0
(-1555 3225);
DISPLAY 0.617021 (-1555 3225);
PAINT AQUA (-1555 3225);
FORCEPROP 1 LAST VALUE 0.0
J 0
(-1555 3175);
DISPLAY 0.617021 (-1555 3175);
PAINT SKYBLUE (-1555 3175);
FORCEPROP 1 LAST TOLERANCE 5%
J 0
(-1555 3125);
DISPLAY 0.617021 (-1555 3125);
PAINT SKYBLUE (-1555 3125);
FORCEPROP 1 LAST WATTAGE 1/16W
J 0
(-1560 3075);
DISPLAY 0.617021 (-1560 3075);
PAINT SKYBLUE (-1560 3075);
FORCEPROP 1 LASTPIN (-1600 3000) $PN 2
J 0
(-1595 3010);
DISPLAY 0.787234 (-1595 3010);
PAINT ORANGE (-1595 3010);
DISPLAY INVISIBLE (-1595 3010);
FORCEPROP 2 LAST CDS_LIB mstr_discrete
J 0
(-1600 3100);
PAINT ORANGE (-1600 3100);
DISPLAY INVISIBLE (-1600 3100);
FORCEPROP 1 LASTPIN (-1600 3200) $PN 1
J 0
(-1595 3162);
DISPLAY 0.787234 (-1595 3162);
PAINT ORANGE (-1595 3162);
DISPLAY INVISIBLE (-1595 3162);
FORCEPROP 2 LAST CDS_LOCATION R2U22
J 0
(-1555 3225);
DISPLAY 0.617021 (-1555 3225);
PAINT AQUA (-1555 3225);
DISPLAY INVISIBLE (-1555 3225);
FORCEPROP 1 LAST PATH I470
J 0
(-1550 3275);
DISPLAY 0.978723 (-1550 3275);
PAINT WHITE (-1550 3275);
DISPLAY INVISIBLE (-1550 3275);
FORCEPROP 2 LAST CDS_SEC 1
J 0
(-1550 3325);
DISPLAY 1.021277 (-1550 3325);
PAINT ORANGE (-1550 3325);
DISPLAY INVISIBLE (-1550 3325);
FORCEPROP 2 LAST $SEC 1
J 0
(-1550 3325);
DISPLAY 0.680851 (-1550 3325);
PAINT MONO (-1550 3325);
DISPLAY INVISIBLE (-1550 3325);
FORCEADD RES..2
(-1800 2800);
FORCEPROP 1 LAST WATTAGE 1/16W
J 0
(-1760 2775);
DISPLAY 0.617021 (-1760 2775);
PAINT SKYBLUE (-1760 2775);
FORCEPROP 1 LAST PACK_TYPE 0402
J 0
(-1760 2625);
DISPLAY 0.617021 (-1760 2625);
PAINT SKYBLUE (-1760 2625);
FORCEPROP 1 LAST MATERIAL EMPTY
J 0
(-1760 2725);
DISPLAY 0.617021 (-1760 2725);
PAINT RED (-1760 2725);
FORCEPROP 1 LAST VALUE 0.0
J 0
(-1755 2875);
DISPLAY 0.617021 (-1755 2875);
PAINT SKYBLUE (-1755 2875);
FORCEPROP 1 LAST TOLERANCE 5%
J 0
(-1755 2825);
DISPLAY 0.617021 (-1755 2825);
PAINT SKYBLUE (-1755 2825);
FORCEPROP 1 LAST LOCATION R2U24
J 0
(-1755 2925);
DISPLAY 0.617021 (-1755 2925);
PAINT AQUA (-1755 2925);
FORCEPROP 1 LAST PART_NUMBER G21497-005
J 0
(-1760 2675);
DISPLAY 0.617021 (-1760 2675);
PAINT BLUE (-1760 2675);
FORCEPROP 1 LASTPIN (-1800 2700) $PN 2
J 0
(-1795 2710);
DISPLAY 0.787234 (-1795 2710);
PAINT ORANGE (-1795 2710);
DISPLAY INVISIBLE (-1795 2710);
FORCEPROP 2 LAST CDS_LIB mstr_discrete
J 0
(-1800 2800);
PAINT ORANGE (-1800 2800);
DISPLAY INVISIBLE (-1800 2800);
FORCEPROP 1 LASTPIN (-1800 2900) $PN 1
J 0
(-1795 2862);
DISPLAY 0.787234 (-1795 2862);
PAINT ORANGE (-1795 2862);
DISPLAY INVISIBLE (-1795 2862);
FORCEPROP 2 LAST CDS_SEC 1
J 0
(-1750 3025);
DISPLAY 1.021277 (-1750 3025);
PAINT ORANGE (-1750 3025);
DISPLAY INVISIBLE (-1750 3025);
FORCEPROP 2 LAST $SEC 1
J 0
(-1750 3025);
DISPLAY 0.680851 (-1750 3025);
PAINT MONO (-1750 3025);
DISPLAY INVISIBLE (-1750 3025);
FORCEPROP 2 LAST CDS_LOCATION R2U24
J 0
(-1755 2925);
DISPLAY 0.617021 (-1755 2925);
PAINT AQUA (-1755 2925);
DISPLAY INVISIBLE (-1755 2925);
FORCEPROP 1 LAST PATH I471
J 0
(-1750 2975);
DISPLAY 0.978723 (-1750 2975);
PAINT WHITE (-1750 2975);
DISPLAY INVISIBLE (-1750 2975);
FORCEADD RES..2
(-2000 3100);
FORCEPROP 1 LAST MATERIAL EMPTY
J 0
(-1960 3025);
DISPLAY 0.617021 (-1960 3025);
PAINT RED (-1960 3025);
FORCEPROP 1 LAST PACK_TYPE 0402
J 0
(-1960 2925);
DISPLAY 0.617021 (-1960 2925);
PAINT SKYBLUE (-1960 2925);
FORCEPROP 1 LAST PART_NUMBER G21497-005
J 0
(-1960 2975);
DISPLAY 0.617021 (-1960 2975);
PAINT BLUE (-1960 2975);
FORCEPROP 1 LAST LOCATION R2U26
J 0
(-1955 3225);
DISPLAY 0.617021 (-1955 3225);
PAINT AQUA (-1955 3225);
FORCEPROP 1 LAST VALUE 0.0
J 0
(-1955 3175);
DISPLAY 0.617021 (-1955 3175);
PAINT SKYBLUE (-1955 3175);
FORCEPROP 1 LAST TOLERANCE 5%
J 0
(-1955 3125);
DISPLAY 0.617021 (-1955 3125);
PAINT SKYBLUE (-1955 3125);
FORCEPROP 1 LAST WATTAGE 1/16W
J 0
(-1960 3075);
DISPLAY 0.617021 (-1960 3075);
PAINT SKYBLUE (-1960 3075);
FORCEPROP 1 LASTPIN (-2000 3000) $PN 2
J 0
(-1995 3010);
DISPLAY 0.787234 (-1995 3010);
PAINT ORANGE (-1995 3010);
DISPLAY INVISIBLE (-1995 3010);
FORCEPROP 1 LASTPIN (-2000 3200) $PN 1
J 0
(-1995 3162);
DISPLAY 0.787234 (-1995 3162);
PAINT ORANGE (-1995 3162);
DISPLAY INVISIBLE (-1995 3162);
FORCEPROP 2 LAST CDS_LIB mstr_discrete
J 0
(-2000 3100);
PAINT ORANGE (-2000 3100);
DISPLAY INVISIBLE (-2000 3100);
FORCEPROP 2 LAST CDS_LOCATION R2U26
J 0
(-1955 3225);
DISPLAY 0.617021 (-1955 3225);
PAINT AQUA (-1955 3225);
DISPLAY INVISIBLE (-1955 3225);
FORCEPROP 1 LAST PATH I472
J 0
(-1950 3275);
DISPLAY 0.978723 (-1950 3275);
PAINT WHITE (-1950 3275);
DISPLAY INVISIBLE (-1950 3275);
FORCEPROP 2 LAST CDS_SEC 1
J 0
(-1950 3325);
DISPLAY 1.021277 (-1950 3325);
PAINT ORANGE (-1950 3325);
DISPLAY INVISIBLE (-1950 3325);
FORCEPROP 2 LAST $SEC 1
J 0
(-1950 3325);
DISPLAY 0.680851 (-1950 3325);
PAINT MONO (-1950 3325);
DISPLAY INVISIBLE (-1950 3325);
FORCEADD RES..2
(-2200 2800);
FORCEPROP 1 LAST TOLERANCE 5%
J 0
(-2155 2825);
DISPLAY 0.617021 (-2155 2825);
PAINT SKYBLUE (-2155 2825);
FORCEPROP 1 LAST VALUE 0.0
J 0
(-2155 2875);
DISPLAY 0.617021 (-2155 2875);
PAINT SKYBLUE (-2155 2875);
FORCEPROP 1 LAST MATERIAL EMPTY
J 0
(-2160 2725);
DISPLAY 0.617021 (-2160 2725);
PAINT RED (-2160 2725);
FORCEPROP 1 LAST LOCATION R2U28
J 0
(-2155 2925);
DISPLAY 0.617021 (-2155 2925);
PAINT AQUA (-2155 2925);
FORCEPROP 1 LAST PART_NUMBER G21497-005
J 0
(-2160 2675);
DISPLAY 0.617021 (-2160 2675);
PAINT BLUE (-2160 2675);
FORCEPROP 1 LAST PACK_TYPE 0402
J 0
(-2160 2625);
DISPLAY 0.617021 (-2160 2625);
PAINT SKYBLUE (-2160 2625);
FORCEPROP 1 LAST WATTAGE 1/16W
J 0
(-2160 2775);
DISPLAY 0.617021 (-2160 2775);
PAINT SKYBLUE (-2160 2775);
FORCEPROP 1 LASTPIN (-2200 2700) $PN 2
J 0
(-2195 2710);
DISPLAY 0.787234 (-2195 2710);
PAINT ORANGE (-2195 2710);
DISPLAY INVISIBLE (-2195 2710);
FORCEPROP 2 LAST CDS_LIB mstr_discrete
J 0
(-2200 2800);
PAINT ORANGE (-2200 2800);
DISPLAY INVISIBLE (-2200 2800);
FORCEPROP 1 LASTPIN (-2200 2900) $PN 1
J 0
(-2195 2862);
DISPLAY 0.787234 (-2195 2862);
PAINT ORANGE (-2195 2862);
DISPLAY INVISIBLE (-2195 2862);
FORCEPROP 2 LAST CDS_LOCATION R2U28
J 0
(-2155 2925);
DISPLAY 0.617021 (-2155 2925);
PAINT AQUA (-2155 2925);
DISPLAY INVISIBLE (-2155 2925);
FORCEPROP 2 LAST $SEC 1
J 0
(-2150 3025);
DISPLAY 0.680851 (-2150 3025);
PAINT MONO (-2150 3025);
DISPLAY INVISIBLE (-2150 3025);
FORCEPROP 2 LAST CDS_SEC 1
J 0
(-2150 3025);
DISPLAY 1.021277 (-2150 3025);
PAINT ORANGE (-2150 3025);
DISPLAY INVISIBLE (-2150 3025);
FORCEPROP 1 LAST PATH I473
J 0
(-2150 2975);
DISPLAY 0.978723 (-2150 2975);
PAINT WHITE (-2150 2975);
DISPLAY INVISIBLE (-2150 2975);
FORCEADD BOM_NOTE..1
(-3350 2950);
FORCEPROP 0 LAST L1 STUFF FOR X24 SS SUPPORT
J 0
(-3450 2825);
DISPLAY 1.021277 (-3450 2825);
PAINT ORANGE (-3450 2825);
FORCEPROP 2 LAST CDS_LIB mstr_symbols
J 0
(-3350 2950);
PAINT ORANGE (-3350 2950);
DISPLAY INVISIBLE (-3350 2950);
FORCEPROP 1 LAST COMMENT_BODY TRUE
J 0
(-3325 3050);
DISPLAY 0.978723 (-3325 3050);
PAINT ORANGE (-3325 3050);
DISPLAY INVISIBLE (-3325 3050);
FORCEADD CAD_NOTE..1
(-3200 2675);
FORCEPROP 0 LAST L1 PLACE CLOSE TO X24 SLOT
J 0
(-3325 2550);
DISPLAY 1.021277 (-3325 2550);
PAINT ORANGE (-3325 2550);
FORCEPROP 2 LAST CDS_LIB mstr_symbols
J 0
(-3200 2675);
PAINT ORANGE (-3200 2675);
DISPLAY INVISIBLE (-3200 2675);
FORCEPROP 1 LAST COMMENT_BODY TRUE
J 0
(-3175 2775);
DISPLAY 0.978723 (-3175 2775);
PAINT ORANGE (-3175 2775);
DISPLAY INVISIBLE (-3175 2775);
FORCEADD BOM_NOTE..1
(-4475 650);
FORCEPROP 0 LAST L1 UNSTUFF FOR X24 SS SUPPORT
J 0
(-4575 525);
DISPLAY 1.021277 (-4575 525);
PAINT ORANGE (-4575 525);
FORCEPROP 2 LAST CDS_LIB mstr_symbols
J 0
(-4475 650);
PAINT ORANGE (-4475 650);
DISPLAY INVISIBLE (-4475 650);
FORCEPROP 1 LAST COMMENT_BODY TRUE
J 0
(-4450 750);
DISPLAY 0.978723 (-4450 750);
PAINT ORANGE (-4450 750);
DISPLAY INVISIBLE (-4450 750);
FORCEADD CAD_NOTE..1
(-4200 350);
FORCEPROP 0 LAST L1 PLACE CLOSE TO PCH
J 0
(-4325 225);
DISPLAY 1.021277 (-4325 225);
PAINT ORANGE (-4325 225);
FORCEPROP 2 LAST CDS_LIB mstr_symbols
J 0
(-4200 350);
PAINT ORANGE (-4200 350);
DISPLAY INVISIBLE (-4200 350);
FORCEPROP 1 LAST COMMENT_BODY TRUE
J 0
(-4175 450);
DISPLAY 0.978723 (-4175 450);
PAINT ORANGE (-4175 450);
DISPLAY INVISIBLE (-4175 450);
FORCEADD DNS..2
(-4295 3970);
PAINT RED (-4295 3970);
FORCEPROP 1 LAST COMMENT_BODY TRUE
R 1
J 0
(-4220 3745);
DISPLAY 0.872340 (-4220 3745);
PAINT GREEN (-4220 3745);
DISPLAY INVISIBLE (-4220 3745);
FORCEPROP 2 LAST CDS_LIB mstr_misc
J 0
(-4295 3970);
PAINT ORANGE (-4295 3970);
DISPLAY INVISIBLE (-4295 3970);
FORCEADD DNS..2
(-4245 2970);
PAINT RED (-4245 2970);
FORCEPROP 1 LAST COMMENT_BODY TRUE
R 1
J 0
(-4170 2745);
DISPLAY 0.872340 (-4170 2745);
PAINT GREEN (-4170 2745);
DISPLAY INVISIBLE (-4170 2745);
FORCEPROP 2 LAST CDS_LIB mstr_misc
J 0
(-4245 2970);
PAINT ORANGE (-4245 2970);
DISPLAY INVISIBLE (-4245 2970);
FORCEADD DNS..2
(-4495 3695);
PAINT RED (-4495 3695);
FORCEPROP 1 LAST COMMENT_BODY TRUE
R 1
J 0
(-4420 3470);
DISPLAY 0.872340 (-4420 3470);
PAINT GREEN (-4420 3470);
DISPLAY INVISIBLE (-4420 3470);
FORCEPROP 2 LAST CDS_LIB mstr_misc
J 0
(-4495 3695);
PAINT ORANGE (-4495 3695);
DISPLAY INVISIBLE (-4495 3695);
FORCEADD DNS..2
(-4695 3970);
PAINT RED (-4695 3970);
FORCEPROP 1 LAST COMMENT_BODY TRUE
R 1
J 0
(-4620 3745);
DISPLAY 0.872340 (-4620 3745);
PAINT GREEN (-4620 3745);
DISPLAY INVISIBLE (-4620 3745);
FORCEPROP 2 LAST CDS_LIB mstr_misc
J 0
(-4695 3970);
PAINT ORANGE (-4695 3970);
DISPLAY INVISIBLE (-4695 3970);
FORCEADD DNS..2
(-4895 3670);
PAINT RED (-4895 3670);
FORCEPROP 1 LAST COMMENT_BODY TRUE
R 1
J 0
(-4820 3445);
DISPLAY 0.872340 (-4820 3445);
PAINT GREEN (-4820 3445);
DISPLAY INVISIBLE (-4820 3445);
FORCEPROP 2 LAST CDS_LIB mstr_misc
J 0
(-4895 3670);
PAINT ORANGE (-4895 3670);
DISPLAY INVISIBLE (-4895 3670);
FORCEADD DNS..2
(-4645 2970);
PAINT RED (-4645 2970);
FORCEPROP 1 LAST COMMENT_BODY TRUE
R 1
J 0
(-4570 2745);
DISPLAY 0.872340 (-4570 2745);
PAINT GREEN (-4570 2745);
DISPLAY INVISIBLE (-4570 2745);
FORCEPROP 2 LAST CDS_LIB mstr_misc
J 0
(-4645 2970);
PAINT ORANGE (-4645 2970);
DISPLAY INVISIBLE (-4645 2970);
FORCEADD DNS..2
(-4445 2670);
PAINT RED (-4445 2670);
FORCEPROP 1 LAST COMMENT_BODY TRUE
R 1
J 0
(-4370 2445);
DISPLAY 0.872340 (-4370 2445);
PAINT GREEN (-4370 2445);
DISPLAY INVISIBLE (-4370 2445);
FORCEPROP 2 LAST CDS_LIB mstr_misc
J 0
(-4445 2670);
PAINT ORANGE (-4445 2670);
DISPLAY INVISIBLE (-4445 2670);
FORCEADD DNS..2
(-4845 2670);
PAINT RED (-4845 2670);
FORCEPROP 1 LAST COMMENT_BODY TRUE
R 1
J 0
(-4770 2445);
DISPLAY 0.872340 (-4770 2445);
PAINT GREEN (-4770 2445);
DISPLAY INVISIBLE (-4770 2445);
FORCEPROP 2 LAST CDS_LIB mstr_misc
J 0
(-4845 2670);
PAINT ORANGE (-4845 2670);
DISPLAY INVISIBLE (-4845 2670);
FORCEADD DNS..2
(-5095 3970);
PAINT RED (-5095 3970);
FORCEPROP 1 LAST COMMENT_BODY TRUE
R 1
J 0
(-5020 3745);
DISPLAY 0.872340 (-5020 3745);
PAINT GREEN (-5020 3745);
DISPLAY INVISIBLE (-5020 3745);
FORCEPROP 2 LAST CDS_LIB mstr_misc
J 0
(-5095 3970);
PAINT ORANGE (-5095 3970);
DISPLAY INVISIBLE (-5095 3970);
FORCEADD DNS..2
(-5495 3970);
PAINT RED (-5495 3970);
FORCEPROP 1 LAST COMMENT_BODY TRUE
R 1
J 0
(-5420 3745);
DISPLAY 0.872340 (-5420 3745);
PAINT GREEN (-5420 3745);
DISPLAY INVISIBLE (-5420 3745);
FORCEPROP 2 LAST CDS_LIB mstr_misc
J 0
(-5495 3970);
PAINT ORANGE (-5495 3970);
DISPLAY INVISIBLE (-5495 3970);
FORCEADD DNS..2
(-5295 3670);
PAINT RED (-5295 3670);
FORCEPROP 1 LAST COMMENT_BODY TRUE
R 1
J 0
(-5220 3445);
DISPLAY 0.872340 (-5220 3445);
PAINT GREEN (-5220 3445);
DISPLAY INVISIBLE (-5220 3445);
FORCEPROP 2 LAST CDS_LIB mstr_misc
J 0
(-5295 3670);
PAINT ORANGE (-5295 3670);
DISPLAY INVISIBLE (-5295 3670);
FORCEADD DNS..2
(-5045 2970);
PAINT RED (-5045 2970);
FORCEPROP 1 LAST COMMENT_BODY TRUE
R 1
J 0
(-4970 2745);
DISPLAY 0.872340 (-4970 2745);
PAINT GREEN (-4970 2745);
DISPLAY INVISIBLE (-4970 2745);
FORCEPROP 2 LAST CDS_LIB mstr_misc
J 0
(-5045 2970);
PAINT ORANGE (-5045 2970);
DISPLAY INVISIBLE (-5045 2970);
FORCEADD DNS..2
(-5445 2970);
PAINT RED (-5445 2970);
FORCEPROP 1 LAST COMMENT_BODY TRUE
R 1
J 0
(-5370 2745);
DISPLAY 0.872340 (-5370 2745);
PAINT GREEN (-5370 2745);
DISPLAY INVISIBLE (-5370 2745);
FORCEPROP 2 LAST CDS_LIB mstr_misc
J 0
(-5445 2970);
PAINT ORANGE (-5445 2970);
DISPLAY INVISIBLE (-5445 2970);
FORCEADD DNS..2
(-5695 3670);
PAINT RED (-5695 3670);
FORCEPROP 1 LAST COMMENT_BODY TRUE
R 1
J 0
(-5620 3445);
DISPLAY 0.872340 (-5620 3445);
PAINT GREEN (-5620 3445);
DISPLAY INVISIBLE (-5620 3445);
FORCEPROP 2 LAST CDS_LIB mstr_misc
J 0
(-5695 3670);
PAINT ORANGE (-5695 3670);
DISPLAY INVISIBLE (-5695 3670);
FORCEADD DNS..2
(-5245 2670);
PAINT RED (-5245 2670);
FORCEPROP 1 LAST COMMENT_BODY TRUE
R 1
J 0
(-5170 2445);
DISPLAY 0.872340 (-5170 2445);
PAINT GREEN (-5170 2445);
DISPLAY INVISIBLE (-5170 2445);
FORCEPROP 2 LAST CDS_LIB mstr_misc
J 0
(-5245 2670);
PAINT ORANGE (-5245 2670);
DISPLAY INVISIBLE (-5245 2670);
FORCEADD DNS..2
(-5645 2670);
PAINT RED (-5645 2670);
FORCEPROP 1 LAST COMMENT_BODY TRUE
R 1
J 0
(-5570 2445);
DISPLAY 0.872340 (-5570 2445);
PAINT GREEN (-5570 2445);
DISPLAY INVISIBLE (-5570 2445);
FORCEPROP 2 LAST CDS_LIB mstr_misc
J 0
(-5645 2670);
PAINT ORANGE (-5645 2670);
DISPLAY INVISIBLE (-5645 2670);
FORCEADD DNS..2
(-2220 3820);
PAINT RED (-2220 3820);
FORCEPROP 1 LAST COMMENT_BODY TRUE
R 1
J 0
(-2145 3595);
DISPLAY 0.872340 (-2145 3595);
PAINT GREEN (-2145 3595);
DISPLAY INVISIBLE (-2145 3595);
FORCEPROP 2 LAST CDS_LIB mstr_misc
J 0
(-2220 3820);
PAINT ORANGE (-2220 3820);
DISPLAY INVISIBLE (-2220 3820);
FORCEADD DNS..2
(-2020 4120);
PAINT RED (-2020 4120);
FORCEPROP 1 LAST COMMENT_BODY TRUE
R 1
J 0
(-1945 3895);
DISPLAY 0.872340 (-1945 3895);
PAINT GREEN (-1945 3895);
DISPLAY INVISIBLE (-1945 3895);
FORCEPROP 2 LAST CDS_LIB mstr_misc
J 0
(-2020 4120);
PAINT ORANGE (-2020 4120);
DISPLAY INVISIBLE (-2020 4120);
FORCEADD DNS..2
(-1820 3820);
PAINT RED (-1820 3820);
FORCEPROP 1 LAST COMMENT_BODY TRUE
R 1
J 0
(-1745 3595);
DISPLAY 0.872340 (-1745 3595);
PAINT GREEN (-1745 3595);
DISPLAY INVISIBLE (-1745 3595);
FORCEPROP 2 LAST CDS_LIB mstr_misc
J 0
(-1820 3820);
PAINT ORANGE (-1820 3820);
DISPLAY INVISIBLE (-1820 3820);
FORCEADD DNS..2
(-1620 4120);
PAINT RED (-1620 4120);
FORCEPROP 1 LAST COMMENT_BODY TRUE
R 1
J 0
(-1545 3895);
DISPLAY 0.872340 (-1545 3895);
PAINT GREEN (-1545 3895);
DISPLAY INVISIBLE (-1545 3895);
FORCEPROP 2 LAST CDS_LIB mstr_misc
J 0
(-1620 4120);
PAINT ORANGE (-1620 4120);
DISPLAY INVISIBLE (-1620 4120);
FORCEADD DNS..2
(-1420 3820);
PAINT RED (-1420 3820);
FORCEPROP 1 LAST COMMENT_BODY TRUE
R 1
J 0
(-1345 3595);
DISPLAY 0.872340 (-1345 3595);
PAINT GREEN (-1345 3595);
DISPLAY INVISIBLE (-1345 3595);
FORCEPROP 2 LAST CDS_LIB mstr_misc
J 0
(-1420 3820);
PAINT ORANGE (-1420 3820);
DISPLAY INVISIBLE (-1420 3820);
FORCEADD DNS..2
(-1220 4120);
PAINT RED (-1220 4120);
FORCEPROP 1 LAST COMMENT_BODY TRUE
R 1
J 0
(-1145 3895);
DISPLAY 0.872340 (-1145 3895);
PAINT GREEN (-1145 3895);
DISPLAY INVISIBLE (-1145 3895);
FORCEPROP 2 LAST CDS_LIB mstr_misc
J 0
(-1220 4120);
PAINT ORANGE (-1220 4120);
DISPLAY INVISIBLE (-1220 4120);
FORCEADD DNS..2
(-1020 3820);
PAINT RED (-1020 3820);
FORCEPROP 1 LAST COMMENT_BODY TRUE
R 1
J 0
(-945 3595);
DISPLAY 0.872340 (-945 3595);
PAINT GREEN (-945 3595);
DISPLAY INVISIBLE (-945 3595);
FORCEPROP 2 LAST CDS_LIB mstr_misc
J 0
(-1020 3820);
PAINT ORANGE (-1020 3820);
DISPLAY INVISIBLE (-1020 3820);
FORCEADD DNS..2
(-820 4120);
PAINT RED (-820 4120);
FORCEPROP 1 LAST COMMENT_BODY TRUE
R 1
J 0
(-745 3895);
DISPLAY 0.872340 (-745 3895);
PAINT GREEN (-745 3895);
DISPLAY INVISIBLE (-745 3895);
FORCEPROP 2 LAST CDS_LIB mstr_misc
J 0
(-820 4120);
PAINT ORANGE (-820 4120);
DISPLAY INVISIBLE (-820 4120);
FORCEADD DNS..2
(-795 3095);
PAINT RED (-795 3095);
FORCEPROP 1 LAST COMMENT_BODY TRUE
R 1
J 0
(-720 2870);
DISPLAY 0.872340 (-720 2870);
PAINT GREEN (-720 2870);
DISPLAY INVISIBLE (-720 2870);
FORCEPROP 2 LAST CDS_LIB mstr_misc
J 0
(-795 3095);
PAINT ORANGE (-795 3095);
DISPLAY INVISIBLE (-795 3095);
FORCEADD DNS..2
(-995 2795);
PAINT RED (-995 2795);
FORCEPROP 1 LAST COMMENT_BODY TRUE
R 1
J 0
(-920 2570);
DISPLAY 0.872340 (-920 2570);
PAINT GREEN (-920 2570);
DISPLAY INVISIBLE (-920 2570);
FORCEPROP 2 LAST CDS_LIB mstr_misc
J 0
(-995 2795);
PAINT ORANGE (-995 2795);
DISPLAY INVISIBLE (-995 2795);
FORCEADD DNS..2
(-1195 3095);
PAINT RED (-1195 3095);
FORCEPROP 1 LAST COMMENT_BODY TRUE
R 1
J 0
(-1120 2870);
DISPLAY 0.872340 (-1120 2870);
PAINT GREEN (-1120 2870);
DISPLAY INVISIBLE (-1120 2870);
FORCEPROP 2 LAST CDS_LIB mstr_misc
J 0
(-1195 3095);
PAINT ORANGE (-1195 3095);
DISPLAY INVISIBLE (-1195 3095);
FORCEADD DNS..2
(-1395 2795);
PAINT RED (-1395 2795);
FORCEPROP 1 LAST COMMENT_BODY TRUE
R 1
J 0
(-1320 2570);
DISPLAY 0.872340 (-1320 2570);
PAINT GREEN (-1320 2570);
DISPLAY INVISIBLE (-1320 2570);
FORCEPROP 2 LAST CDS_LIB mstr_misc
J 0
(-1395 2795);
PAINT ORANGE (-1395 2795);
DISPLAY INVISIBLE (-1395 2795);
FORCEADD DNS..2
(-1595 3095);
PAINT RED (-1595 3095);
FORCEPROP 1 LAST COMMENT_BODY TRUE
R 1
J 0
(-1520 2870);
DISPLAY 0.872340 (-1520 2870);
PAINT GREEN (-1520 2870);
DISPLAY INVISIBLE (-1520 2870);
FORCEPROP 2 LAST CDS_LIB mstr_misc
J 0
(-1595 3095);
PAINT ORANGE (-1595 3095);
DISPLAY INVISIBLE (-1595 3095);
FORCEADD DNS..2
(-1795 2795);
PAINT RED (-1795 2795);
FORCEPROP 1 LAST COMMENT_BODY TRUE
R 1
J 0
(-1720 2570);
DISPLAY 0.872340 (-1720 2570);
PAINT GREEN (-1720 2570);
DISPLAY INVISIBLE (-1720 2570);
FORCEPROP 2 LAST CDS_LIB mstr_misc
J 0
(-1795 2795);
PAINT ORANGE (-1795 2795);
DISPLAY INVISIBLE (-1795 2795);
FORCEADD DNS..2
(-1995 3095);
PAINT RED (-1995 3095);
FORCEPROP 1 LAST COMMENT_BODY TRUE
R 1
J 0
(-1920 2870);
DISPLAY 0.872340 (-1920 2870);
PAINT GREEN (-1920 2870);
DISPLAY INVISIBLE (-1920 2870);
FORCEPROP 2 LAST CDS_LIB mstr_misc
J 0
(-1995 3095);
PAINT ORANGE (-1995 3095);
DISPLAY INVISIBLE (-1995 3095);
FORCEADD DNS..2
(-2195 2795);
PAINT RED (-2195 2795);
FORCEPROP 1 LAST COMMENT_BODY TRUE
R 1
J 0
(-2120 2570);
DISPLAY 0.872340 (-2120 2570);
PAINT GREEN (-2120 2570);
DISPLAY INVISIBLE (-2120 2570);
FORCEPROP 2 LAST CDS_LIB mstr_misc
J 0
(-2195 2795);
PAINT ORANGE (-2195 2795);
DISPLAY INVISIBLE (-2195 2795);
FORCEADD INTEL_CORP_BPAGE..1
(125 -275);
FORCEPROP 1 LAST CDS_CON_LAST_MODIFIED Tue Dec 01 11:51:53 2015
J 0
(-1300 50);
DISPLAY 1.595745 (-1300 50);
PAINT GREEN (-1300 50);
DISPLAY INVISIBLE (-1300 50);
FORCEPROP 1 LAST CUSTOM_TXT_CDS <CURRENT_DESIGN_SHEET> OF <TOTAL_DESIGN_SHEETS>
J 0
(-375 -250);
PAINT GREEN (-375 -250);
FORCEPROP 1 LAST CUSTOM_TXT_CDS <CON_LAST_MODIFIED>
J 0
(-1800 75);
PAINT GREEN (-1800 75);
FORCEPROP 2 LAST CUSTOM_TXT_CDS <XR_PAGE_TITLE>
J 0
(-7765 4975);
DISPLAY 0.638298 (-7765 4975);
PAINT PINK (-7765 4975);
DISPLAY INVISIBLE (-7765 4975);
FORCEPROP 1 LAST SCH_TITLE PCIE STEERING
J 0
(-7825 -225);
DISPLAY 1.212766 (-7825 -225);
PAINT ORANGE (-7825 -225);
FORCEPROP 1 LAST SCH_ADDRESS3 Santa Clara, CA 95052-8119
J 0
(-3850 -250);
DISPLAY 0.617021 (-3850 -250);
PAINT GREEN (-3850 -250);
FORCEPROP 1 LAST SCH_ADDRESS2 P.O. BOX 58119
J 0
(-3850 -200);
DISPLAY 0.617021 (-3850 -200);
PAINT GREEN (-3850 -200);
FORCEPROP 1 LAST SCH_ADDRESS1 2200 Mission College Blvd.
J 0
(-3850 -150);
DISPLAY 0.617021 (-3850 -150);
PAINT GREEN (-3850 -150);
FORCEPROP 1 LAST SCH_NUMBER H4694802
J 0
(-1175 -125);
DISPLAY 1.212766 (-1175 -125);
PAINT YELLOW (-1175 -125);
FORCEPROP 1 LAST SCH_DEPT BESD
J 1
(-4325 -175);
DISPLAY 1.212766 (-4325 -175);
PAINT YELLOW (-4325 -175);
FORCEPROP 1 LAST SCH_REV 2.420
J 0
(-125 -125);
DISPLAY 0.978723 (-125 -125);
PAINT YELLOW (-125 -125);
FORCEPROP 2 LAST PAGE_BORDER TRUE
J 0
(-7765 4975);
PAINT PINK (-7765 4975);
DISPLAY INVISIBLE (-7765 4975);
FORCEPROP 2 LAST CDS_LIB mstr_symbols
J 0
(125 -275);
DISPLAY 1.595745 (125 -275);
PAINT ORANGE (125 -275);
DISPLAY INVISIBLE (125 -275);
FORCEPROP 1 LAST COMMENT_BODY TRUE
J 0
(137 -263);
DISPLAY 0.744681 (137 -263);
PAINT GREEN (137 -263);
DISPLAY INVISIBLE (137 -263);
FORCEPROP 2 LAST CDS_XR_PAGE_TITLE CR-107 : @BASEBOARD_FAB2_LIB.BASEBOARD_FAB2(SCH_1):PAGE107
J 0
(-7765 4975);
DISPLAY 0.638298 (-7765 4975);
PAINT PINK (-7765 4975);
DISPLAY INVISIBLE (-7765 4975);
WIRE 17 -1 (-6850 275)(-6650 275);
WIRE 17 -1 (-6650 275)(-6450 275);
WIRE 17 -1 (-6450 275)(-6250 275);
WIRE 17 -1 (-6250 275)(-6050 275);
FORCEPROP 2 LAST SIG_NAME P3E_CPU0_PE1_PCH_TXP<7:0>
J 0
(-6085 235);
DISPLAY 0.617021 (-6085 235);
PAINT ORANGE (-6085 235);
WIRE 17 -1 (-6900 1175)(-6700 1175);
WIRE 17 -1 (-7000 1175)(-6900 1175);
FORCEPROP 2 LAST SIG_NAME P3E_CPU0_PE1_SS_TXP<7:0>
J 0
(-6960 1185);
DISPLAY 0.617021 (-6960 1185);
PAINT ORANGE (-6960 1185);
WIRE 17 -1 (-6700 1175)(-6500 1175);
WIRE 17 -1 (-6500 1175)(-6300 1175);
WIRE 17 -1 (-6300 1175)(-6100 1175);
WIRE 17 -1 (-6100 1175)(-5900 1175);
WIRE 17 -1 (-6900 1275)(-6700 1275);
WIRE 17 -1 (-6700 1275)(-6500 1275);
WIRE 17 -1 (-6500 1275)(-6300 1275);
WIRE 17 -1 (-6300 1275)(-6100 1275);
WIRE 17 -1 (-6100 1275)(-5900 1275);
FORCEPROP 2 LAST SIG_NAME P3E_CPU0_PE1_PCH_TXN<7:0>
J 0
(-6035 1235);
DISPLAY 0.617021 (-6035 1235);
PAINT ORANGE (-6035 1235);
WIRE 17 -1 (-6950 2175)(-6750 2175);
WIRE 17 -1 (-7050 2175)(-6950 2175);
FORCEPROP 2 LAST SIG_NAME P3E_CPU0_PE1_SS_TXN<7:0>
J 0
(-7035 2185);
DISPLAY 0.617021 (-7035 2185);
PAINT ORANGE (-7035 2185);
WIRE 17 -1 (-6750 2175)(-6550 2175);
WIRE 17 -1 (-6550 2175)(-6350 2175);
WIRE 17 -1 (-6350 2175)(-6150 2175);
WIRE 17 -1 (-6150 2175)(-5950 2175);
WIRE 17 -1 (-5850 275)(-5650 275);
WIRE 17 -1 (-6050 275)(-5850 275);
WIRE 17 -1 (-5650 275)(-5450 275);
WIRE 17 -1 (-5450 275)(-5300 275);
WIRE 17 -1 (-5900 1175)(-5700 1175);
WIRE 17 -1 (-5700 1175)(-5500 1175);
WIRE 17 -1 (-5900 1275)(-5700 1275);
WIRE 17 -1 (-5700 1275)(-5500 1275);
WIRE 17 -1 (-5500 1275)(-5325 1275);
WIRE 17 -1 (-5950 2175)(-5750 2175);
WIRE 17 -1 (-5750 2175)(-5550 2175);
WIRE 17 -1 (-5625 2375)(-5425 2375);
WIRE 17 -1 (-5425 2375)(-5225 2375);
WIRE 17 -1 (-5225 2375)(-5025 2375);
WIRE 17 -1 (-5025 2375)(-4825 2375);
WIRE 17 -1 (-4825 2375)(-4625 2375);
FORCEPROP 2 LAST SIG_NAME P3E_CPU0_PE1_SS_C_TXP<7:0>
J 0
(-4685 2335);
DISPLAY 0.617021 (-4685 2335);
PAINT ORANGE (-4685 2335);
WIRE 17 -1 (-5675 3275)(-5475 3275);
WIRE 17 -1 (-5900 3275)(-5675 3275);
FORCEPROP 2 LAST SIG_NAME P3E_CPU0_PE1_SS_TXP<7:0>
J 0
(-5860 3285);
DISPLAY 0.617021 (-5860 3285);
PAINT ORANGE (-5860 3285);
WIRE 17 -1 (-5475 3275)(-5275 3275);
WIRE 17 -1 (-5275 3275)(-5075 3275);
WIRE 17 -1 (-5075 3275)(-4875 3275);
WIRE 17 -1 (-5675 3375)(-5475 3375);
WIRE 17 -1 (-5475 3375)(-5275 3375);
WIRE 17 -1 (-5275 3375)(-5075 3375);
WIRE 17 -1 (-5075 3375)(-4875 3375);
WIRE 17 -1 (-4875 3375)(-4675 3375);
FORCEPROP 2 LAST SIG_NAME P3E_CPU0_PE1_SS_C_TXN<7:0>
J 0
(-4735 3335);
DISPLAY 0.617021 (-4735 3335);
PAINT ORANGE (-4735 3335);
WIRE 17 -1 (-4625 2375)(-4425 2375);
WIRE 17 -1 (-4425 2375)(-4225 2375);
WIRE 17 -1 (-4225 2375)(-4075 2375);
WIRE 17 -1 (-4875 3275)(-4675 3275);
WIRE 17 -1 (-4675 3275)(-4475 3275);
WIRE 17 -1 (-4475 3275)(-4275 3275);
WIRE 17 -1 (-4675 3375)(-4475 3375);
WIRE 17 -1 (-4475 3375)(-4275 3375);
WIRE 17 -1 (-4275 3375)(-4100 3375);
WIRE 17 -1 (-5725 4275)(-5525 4275);
WIRE 17 -1 (-5950 4275)(-5725 4275);
FORCEPROP 2 LAST SIG_NAME P3E_CPU0_PE1_SS_TXN<7:0>
J 0
(-5885 4285);
DISPLAY 0.617021 (-5885 4285);
PAINT ORANGE (-5885 4285);
WIRE 17 -1 (-5525 4275)(-5325 4275);
WIRE 17 -1 (-5325 4275)(-5125 4275);
WIRE 17 -1 (-5125 4275)(-4925 4275);
WIRE 17 -1 (-4925 4275)(-4725 4275);
WIRE 17 -1 (-4725 4275)(-4525 4275);
WIRE 17 -1 (-4525 4275)(-4325 4275);
WIRE 17 -1 (-3275 225)(-3075 225);
WIRE 17 -1 (-3075 225)(-2875 225);
WIRE 17 -1 (-2875 225)(-2675 225);
WIRE 17 -1 (-2675 225)(-2475 225);
FORCEPROP 2 LAST SIG_NAME P3E_CPU0_PE1_SS_RXP<7:0>
J 0
(-2510 185);
DISPLAY 0.617021 (-2510 185);
PAINT ORANGE (-2510 185);
WIRE 17 -1 (-3325 1125)(-3125 1125);
WIRE 17 -1 (-3425 1125)(-3325 1125);
FORCEPROP 2 LAST SIG_NAME P3E_CPU0_PE1_PCH_RXP<7:0>
J 0
(-3385 1135);
DISPLAY 0.617021 (-3385 1135);
PAINT ORANGE (-3385 1135);
WIRE 17 -1 (-3325 1225)(-3125 1225);
WIRE 17 -1 (-3125 1225)(-2925 1225);
WIRE 17 -1 (-2925 1225)(-2725 1225);
WIRE 17 -1 (-2725 1225)(-2525 1225);
FORCEPROP 2 LAST SIG_NAME P3E_CPU0_PE1_SS_RXN<7:0>
J 0
(-2535 1185);
DISPLAY 0.617021 (-2535 1185);
PAINT ORANGE (-2535 1185);
WIRE 17 -1 (-3375 2125)(-3175 2125);
WIRE 17 -1 (-3475 2125)(-3375 2125);
FORCEPROP 2 LAST SIG_NAME P3E_CPU0_PE1_PCH_RXN<7:0>
J 0
(-3435 2135);
DISPLAY 0.617021 (-3435 2135);
PAINT ORANGE (-3435 2135);
WIRE 17 -1 (-2275 225)(-2075 225);
WIRE 17 -1 (-2475 225)(-2275 225);
WIRE 17 -1 (-2075 225)(-1875 225);
WIRE 17 -1 (-1875 225)(-1725 225);
WIRE 17 -1 (-3125 1125)(-2925 1125);
WIRE 17 -1 (-2925 1125)(-2725 1125);
WIRE 17 -1 (-2725 1125)(-2525 1125);
WIRE 17 -1 (-2525 1125)(-2325 1125);
WIRE 17 -1 (-2325 1125)(-2125 1125);
WIRE 17 -1 (-2125 1125)(-1925 1125);
WIRE 17 -1 (-3175 2125)(-2975 2125);
WIRE 17 -1 (-2975 2125)(-2775 2125);
WIRE 17 -1 (-2775 2125)(-2575 2125);
WIRE 17 -1 (-2575 2125)(-2375 2125);
WIRE 17 -1 (-2325 1225)(-2125 1225);
WIRE 17 -1 (-2525 1225)(-2325 1225);
WIRE 17 -1 (-2125 1225)(-1925 1225);
WIRE 17 -1 (-1925 1225)(-1750 1225);
WIRE 17 -1 (-2375 2125)(-2175 2125);
WIRE 17 -1 (-2175 2125)(-1975 2125);
WIRE 17 -1 (-2175 2500)(-1975 2500);
WIRE 17 -1 (-1975 2500)(-1775 2500);
WIRE 17 -1 (-1775 2500)(-1575 2500);
WIRE 17 -1 (-1575 2500)(-1375 2500);
FORCEPROP 2 LAST SIG_NAME P3E_CPU0_PE1_SS_RXP<7:0>
J 0
(-1435 2460);
DISPLAY 0.617021 (-1435 2460);
PAINT ORANGE (-1435 2460);
WIRE 17 -1 (-2225 3400)(-2025 3400);
WIRE 17 -1 (-2325 3400)(-2225 3400);
FORCEPROP 2 LAST SIG_NAME P3E_CPU0_PE1_SS_R_RXP<7:0>
J 0
(-2285 3410);
DISPLAY 0.617021 (-2285 3410);
PAINT ORANGE (-2285 3410);
WIRE 17 -1 (-2200 3525)(-2000 3525);
WIRE 17 -1 (-2000 3525)(-1800 3525);
WIRE 17 -1 (-1800 3525)(-1600 3525);
WIRE 17 -1 (-1600 3525)(-1400 3525);
FORCEPROP 2 LAST SIG_NAME P3E_CPU0_PE1_SS_RXN<7:0>
J 0
(-1385 3485);
DISPLAY 0.617021 (-1385 3485);
PAINT ORANGE (-1385 3485);
WIRE 17 -1 (-1375 2500)(-1175 2500);
WIRE 17 -1 (-2025 3400)(-1825 3400);
WIRE 17 -1 (-1825 3400)(-1625 3400);
WIRE 17 -1 (-1625 3400)(-1425 3400);
WIRE 17 -1 (-1425 3400)(-1225 3400);
WIRE 17 -1 (-1225 3400)(-1025 3400);
WIRE 17 -1 (-1025 3400)(-825 3400);
WIRE 17 -1 (-1200 3525)(-1000 3525);
WIRE 17 -1 (-1400 3525)(-1200 3525);
WIRE 17 -1 (-1000 3525)(-800 3525);
WIRE 17 -1 (-800 3525)(-725 3525);
WIRE 17 -1 (-1175 2500)(-975 2500);
WIRE 17 -1 (-975 2500)(-775 2500);
WIRE 17 -1 (-775 2500)(-650 2500);
WIRE 17 -1 (-2250 4425)(-2050 4425);
WIRE 17 -1 (-2450 4425)(-2250 4425);
FORCEPROP 2 LAST SIG_NAME P3E_CPU0_PE1_SS_R_RXN<7:0>
J 0
(-2410 4435);
DISPLAY 0.617021 (-2410 4435);
PAINT ORANGE (-2410 4435);
WIRE 17 -1 (-2050 4425)(-1850 4425);
WIRE 17 -1 (-1850 4425)(-1650 4425);
WIRE 17 -1 (-1650 4425)(-1450 4425);
WIRE 17 -1 (-1450 4425)(-1250 4425);
WIRE 17 -1 (-1250 4425)(-1050 4425);
WIRE 17 -1 (-1050 4425)(-850 4425);
WIRE 16 273 (-7700 2250)(0 2250);
WIRE 16 -1 (-825 4325)(-825 4225);
WIRE 16 -1 (-1225 4325)(-1225 4225);
WIRE 16 -1 (-1625 4325)(-1625 4225);
WIRE 16 -1 (-2025 4325)(-2025 4225);
WIRE 16 -1 (-1025 4325)(-1025 3925);
WIRE 16 -1 (-1425 4325)(-1425 3925);
WIRE 16 -1 (-1825 4325)(-1825 3925);
WIRE 16 -1 (-2225 4325)(-2225 3925);
WIRE 16 -1 (-825 4025)(-825 3625);
WIRE 16 -1 (-800 3300)(-800 3200);
WIRE 16 -1 (-1000 3300)(-1000 2900);
WIRE 16 -1 (-800 3000)(-800 2600);
WIRE 16 -1 (-1000 2700)(-1000 2600);
WIRE 16 -1 (-1225 4025)(-1225 3625);
WIRE 16 -1 (-1025 3725)(-1025 3625);
WIRE 16 -1 (-1425 3725)(-1425 3625);
WIRE 16 -1 (-1200 3300)(-1200 3200);
WIRE 16 -1 (-1625 4025)(-1625 3625);
WIRE 16 -1 (-2025 4025)(-2025 3625);
WIRE 16 -1 (-1825 3725)(-1825 3625);
WIRE 16 -1 (-1600 3300)(-1600 3200);
WIRE 16 -1 (-2000 3300)(-2000 3200);
WIRE 16 -1 (-1400 3300)(-1400 2900);
WIRE 16 -1 (-1800 3300)(-1800 2900);
WIRE 16 -1 (-1200 3000)(-1200 2600);
WIRE 16 -1 (-1400 2700)(-1400 2600);
WIRE 16 -1 (-1600 3000)(-1600 2600);
WIRE 16 -1 (-2000 3000)(-2000 2600);
WIRE 16 -1 (-1800 2700)(-1800 2600);
WIRE 16 -1 (-1950 2025)(-1950 1925);
WIRE 16 -1 (-1950 1725)(-1950 1325);
WIRE 16 -1 (-1900 1025)(-1900 925);
WIRE 16 -1 (-1900 725)(-1900 325);
WIRE 16 -1 (-2225 3725)(-2225 3625);
WIRE 16 -1 (-2200 3300)(-2200 2900);
WIRE 16 -1 (-2200 2700)(-2200 2600);
WIRE 16 -1 (-2150 2025)(-2150 1625);
WIRE 16 -1 (-2350 2025)(-2350 1925);
WIRE 16 -1 (-2550 2025)(-2550 1625);
WIRE 16 -1 (-2350 1725)(-2350 1325);
WIRE 16 -1 (-2150 1425)(-2150 1325);
WIRE 16 -1 (-2550 1425)(-2550 1325);
WIRE 16 -1 (-2750 2025)(-2750 1925);
WIRE 16 -1 (-2950 2025)(-2950 1625);
WIRE 16 -1 (-2750 1725)(-2750 1325);
WIRE 16 -1 (-2950 1425)(-2950 1325);
WIRE 16 -1 (-2100 1025)(-2100 625);
WIRE 16 -1 (-2300 1025)(-2300 925);
WIRE 16 -1 (-2500 1025)(-2500 625);
WIRE 16 -1 (-2700 1025)(-2700 925);
WIRE 16 -1 (-2900 1025)(-2900 625);
WIRE 16 -1 (-2300 725)(-2300 325);
WIRE 16 -1 (-2100 425)(-2100 325);
WIRE 16 -1 (-2500 425)(-2500 325);
WIRE 16 -1 (-2700 725)(-2700 325);
WIRE 16 -1 (-2900 425)(-2900 325);
WIRE 16 -1 (-3150 2025)(-3150 1925);
WIRE 16 -1 (-3350 2025)(-3350 1625);
WIRE 16 -1 (-3150 1725)(-3150 1325);
WIRE 16 -1 (-3350 1425)(-3350 1325);
WIRE 16 -1 (-3100 1025)(-3100 925);
WIRE 16 -1 (-3300 1025)(-3300 625);
WIRE 16 -1 (-3100 725)(-3100 325);
WIRE 16 -1 (-3300 425)(-3300 325);
WIRE 16 -1 (-5500 4175)(-5500 4075);
WIRE 16 -1 (-4300 4075)(-4300 4175);
WIRE 16 -1 (-4500 4175)(-4500 3800);
WIRE 16 -1 (-4700 4075)(-4700 4175);
WIRE 16 -1 (-4900 4175)(-4900 3775);
WIRE 16 -1 (-5100 4175)(-5100 4075);
WIRE 16 -1 (-5300 4175)(-5300 3775);
WIRE 16 -1 (-5700 4175)(-5700 3775);
WIRE 16 -1 (-4300 3475)(-4300 3875);
WIRE 16 -1 (-4500 3600)(-4500 3475);
WIRE 16 -1 (-4250 3175)(-4250 3075);
WIRE 16 -1 (-4700 3475)(-4700 3875);
WIRE 16 -1 (-5100 3875)(-5100 3475);
WIRE 16 -1 (-4650 3175)(-4650 3075);
WIRE 16 -1 (-4900 3575)(-4900 3475);
WIRE 16 -1 (-5050 3175)(-5050 3075);
WIRE 16 -1 (-4450 3175)(-4450 2775);
WIRE 16 -1 (-4850 3175)(-4850 2775);
WIRE 16 -1 (-4250 2875)(-4250 2475);
WIRE 16 -1 (-4450 2575)(-4450 2475);
WIRE 16 -1 (-4650 2875)(-4650 2475);
WIRE 16 -1 (-4850 2575)(-4850 2475);
WIRE 16 -1 (-5050 2875)(-5050 2475);
WIRE 16 -1 (-5500 3875)(-5500 3475);
WIRE 16 -1 (-5300 3575)(-5300 3475);
WIRE 16 -1 (-5450 3175)(-5450 3075);
WIRE 16 -1 (-5700 3575)(-5700 3475);
WIRE 16 -1 (-5250 3175)(-5250 2775);
WIRE 16 -1 (-5650 3175)(-5650 2775);
WIRE 16 -1 (-5250 2575)(-5250 2475);
WIRE 16 -1 (-5450 2875)(-5450 2475);
WIRE 16 -1 (-5650 2575)(-5650 2475);
WIRE 16 -1 (-5525 2075)(-5525 1975);
WIRE 16 -1 (-5725 2075)(-5725 1675);
WIRE 16 -1 (-6125 2075)(-6125 1675);
WIRE 16 -1 (-5925 2000)(-5925 2075);
WIRE 16 -1 (-5525 1775)(-5525 1375);
WIRE 16 -1 (-5925 1375)(-5925 1800);
WIRE 16 -1 (-5725 1475)(-5725 1375);
WIRE 16 -1 (-6125 1475)(-6125 1375);
WIRE 16 -1 (-5475 1075)(-5475 975);
WIRE 16 -1 (-5875 1075)(-5875 975);
WIRE 16 -1 (-5675 1075)(-5675 675);
WIRE 16 -1 (-6075 1075)(-6075 675);
WIRE 16 -1 (-5475 775)(-5475 375);
WIRE 16 -1 (-5875 775)(-5875 375);
WIRE 16 -1 (-5675 475)(-5675 375);
WIRE 16 -1 (-6075 475)(-6075 375);
WIRE 16 -1 (-6325 1975)(-6325 2075);
WIRE 16 -1 (-6725 2075)(-6725 1975);
WIRE 16 -1 (-6525 2075)(-6525 1675);
WIRE 16 -1 (-6925 2075)(-6925 1675);
WIRE 16 -1 (-6325 1375)(-6325 1775);
WIRE 16 -1 (-6525 1475)(-6525 1375);
WIRE 16 -1 (-6725 1775)(-6725 1375);
WIRE 16 -1 (-6925 1475)(-6925 1375);
WIRE 16 -1 (-6275 1075)(-6275 975);
WIRE 16 -1 (-6675 1075)(-6675 975);
WIRE 16 -1 (-6475 1075)(-6475 675);
WIRE 16 -1 (-6875 1075)(-6875 675);
WIRE 16 -1 (-6275 775)(-6275 375);
WIRE 16 -1 (-6475 475)(-6475 375);
WIRE 16 -1 (-6675 775)(-6675 375);
WIRE 16 -1 (-6875 475)(-6875 375);
FORCENOTE
CPU0 <-> PCH PCIEUP
(-1450 2000) 0;
DISPLAY LEFT (-1450 2000);
DISPLAY 2.000000 (-1450 2000);
PAINT PURPLE (-1450 2000);
FORCENOTE
TO CPU0
(-300 3025) 0;
DISPLAY LEFT (-300 3025);
DISPLAY 1.021277 (-300 3025);
PAINT PURPLE (-300 3025);
FORCENOTE
TO CPU0
(-1325 700) 0;
DISPLAY LEFT (-1325 700);
DISPLAY 1.021277 (-1325 700);
PAINT PURPLE (-1325 700);
FORCENOTE
FROM X24 SUPER SLOT
(-3250 3925) 0;
DISPLAY LEFT (-3250 3925);
DISPLAY 1.021277 (-3250 3925);
PAINT PURPLE (-3250 3925);
FORCENOTE
TO X24 SUPER SLOT
(-3925 3100) 0;
DISPLAY LEFT (-3925 3100);
DISPLAY 1.021277 (-3925 3100);
PAINT PURPLE (-3925 3100);
FORCENOTE
FROM PCH PCIEUP 
(-4400 1750) 0;
DISPLAY LEFT (-4400 1750);
DISPLAY 1.021277 (-4400 1750);
PAINT PURPLE (-4400 1750);
FORCENOTE
CPU0 TO PCIE X24 SLOT TX CAPS
(-6025 4375) 0;
DISPLAY LEFT (-6025 4375);
DISPLAY 1.021277 (-6025 4375);
PAINT PURPLE (-6025 4375);
FORCENOTE
DE NOTE:
(-6025 4450) 0;
DISPLAY LEFT (-6025 4450);
DISPLAY 1.021277 (-6025 4450);
PAINT PURPLE (-6025 4450);
FORCENOTE
TO PCH PCIEUP
(-5050 925) 0;
DISPLAY LEFT (-5050 925);
DISPLAY 1.021277 (-5050 925);
PAINT PURPLE (-5050 925);
FORCENOTE
FROM CPU 0
(-6900 3725) 0;
DISPLAY LEFT (-6900 3725);
DISPLAY 1.021277 (-6900 3725);
PAINT PURPLE (-6900 3725);
FORCENOTE
FROM CPU 0
(-7725 1625) 0;
DISPLAY LEFT (-7725 1625);
DISPLAY 1.021277 (-7725 1625);
PAINT PURPLE (-7725 1625);
FORCENOTE
CPU0 <-> X24 SUPER SLOT
(-7700 2400) 0;
DISPLAY LEFT (-7700 2400);
DISPLAY 2.000000 (-7700 2400);
PAINT PURPLE (-7700 2400);
QUIT
